(kicad_sch
	(version 20250114)
	(generator "eeschema")
	(generator_version "9.0")
	(paper "A3")
	(title_block
		(title "Thunderbolt to 10GbE adapter")
		(date "2026-04-23")
		(rev "1.1.0")
		(company "Antmicro Ltd")
		(comment 1 "www.antmicro.com")
	)
	(bus_alias "I2C"
		(members "SDA" "SCL" "IRQ")
	)
	(bus_alias "MDIO"
		(members "MDIO" "MDC")
	)
	(bus_alias "NCSI"
		(members "ARB_IN" "ARB_OUT" "REF_CLK" "CRS_DV" "TX_EN" "TXD_0" "RXD_0"
			"TXD_1" "RXD_1"
		)
	)
	(bus_alias "SPI"
		(members "~{CE}" "CLK" "MISO" "MOSI")
	)
	(text "X710-AT2 Miscellaneous"
		(exclude_from_sim no)
		(at 215.9 25.4 0)
		(effects
			(font
				(size 2.54 2.54)
				(thickness 0.508)
				(bold yes)
			)
		)
	)
	(junction
		(at 306.07 111.76)
		(diameter 0)
		(color 0 0 0 0)
	)
	(junction
		(at 168.91 73.66)
		(diameter 0)
		(color 0 0 0 0)
	)
	(junction
		(at 176.53 124.46)
		(diameter 0)
		(color 0 0 0 0)
	)
	(junction
		(at 285.75 157.48)
		(diameter 0)
		(color 0 0 0 0)
	)
	(junction
		(at 314.96 124.46)
		(diameter 0)
		(color 0 0 0 0)
	)
	(junction
		(at 176.53 104.14)
		(diameter 0)
		(color 0 0 0 0)
	)
	(junction
		(at 200.66 198.12)
		(diameter 0)
		(color 0 0 0 0)
	)
	(junction
		(at 158.75 129.54)
		(diameter 0)
		(color 0 0 0 0)
	)
	(junction
		(at 283.21 223.52)
		(diameter 0)
		(color 0 0 0 0)
	)
	(junction
		(at 73.66 111.76)
		(diameter 0)
		(color 0 0 0 0)
	)
	(junction
		(at 314.96 121.92)
		(diameter 0)
		(color 0 0 0 0)
	)
	(junction
		(at 133.35 234.95)
		(diameter 0)
		(color 0 0 0 0)
	)
	(junction
		(at 297.18 96.52)
		(diameter 0)
		(color 0 0 0 0)
	)
	(junction
		(at 107.95 179.07)
		(diameter 0)
		(color 0 0 0 0)
	)
	(junction
		(at 195.58 114.3)
		(diameter 0)
		(color 0 0 0 0)
	)
	(junction
		(at 186.69 60.96)
		(diameter 0)
		(color 0 0 0 0)
	)
	(junction
		(at 283.21 226.06)
		(diameter 0)
		(color 0 0 0 0)
	)
	(junction
		(at 133.35 220.98)
		(diameter 0)
		(color 0 0 0 0)
	)
	(junction
		(at 93.98 237.49)
		(diameter 0)
		(color 0 0 0 0)
	)
	(junction
		(at 283.21 218.44)
		(diameter 0)
		(color 0 0 0 0)
	)
	(junction
		(at 168.91 167.64)
		(diameter 0)
		(color 0 0 0 0)
	)
	(junction
		(at 283.21 220.98)
		(diameter 0)
		(color 0 0 0 0)
	)
	(junction
		(at 186.69 104.14)
		(diameter 0)
		(color 0 0 0 0)
	)
	(junction
		(at 162.56 68.58)
		(diameter 0)
		(color 0 0 0 0)
	)
	(junction
		(at 107.95 220.98)
		(diameter 0)
		(color 0 0 0 0)
	)
	(junction
		(at 151.13 104.14)
		(diameter 0)
		(color 0 0 0 0)
	)
	(junction
		(at 167.64 127)
		(diameter 0)
		(color 0 0 0 0)
	)
	(junction
		(at 281.94 167.64)
		(diameter 0)
		(color 0 0 0 0)
	)
	(junction
		(at 180.34 63.5)
		(diameter 0)
		(color 0 0 0 0)
	)
	(junction
		(at 133.35 193.04)
		(diameter 0)
		(color 0 0 0 0)
	)
	(junction
		(at 177.8 71.12)
		(diameter 0)
		(color 0 0 0 0)
	)
	(junction
		(at 138.43 179.07)
		(diameter 0)
		(color 0 0 0 0)
	)
	(junction
		(at 204.47 195.58)
		(diameter 0)
		(color 0 0 0 0)
	)
	(junction
		(at 160.02 76.2)
		(diameter 0)
		(color 0 0 0 0)
	)
	(junction
		(at 297.18 109.22)
		(diameter 0)
		(color 0 0 0 0)
	)
	(junction
		(at 151.13 48.26)
		(diameter 0)
		(color 0 0 0 0)
	)
	(junction
		(at 204.47 185.42)
		(diameter 0)
		(color 0 0 0 0)
	)
	(junction
		(at 137.16 220.98)
		(diameter 0)
		(color 0 0 0 0)
	)
	(junction
		(at 151.13 78.74)
		(diameter 0)
		(color 0 0 0 0)
	)
	(junction
		(at 285.75 170.18)
		(diameter 0)
		(color 0 0 0 0)
	)
	(junction
		(at 102.87 220.98)
		(diameter 0)
		(color 0 0 0 0)
	)
	(junction
		(at 189.23 58.42)
		(diameter 0)
		(color 0 0 0 0)
	)
	(junction
		(at 158.75 104.14)
		(diameter 0)
		(color 0 0 0 0)
	)
	(junction
		(at 146.05 237.49)
		(diameter 0)
		(color 0 0 0 0)
	)
	(junction
		(at 306.07 96.52)
		(diameter 0)
		(color 0 0 0 0)
	)
	(junction
		(at 186.69 116.84)
		(diameter 0)
		(color 0 0 0 0)
	)
	(junction
		(at 154.94 127)
		(diameter 0)
		(color 0 0 0 0)
	)
	(junction
		(at 171.45 66.04)
		(diameter 0)
		(color 0 0 0 0)
	)
	(junction
		(at 213.36 185.42)
		(diameter 0)
		(color 0 0 0 0)
	)
	(junction
		(at 167.64 104.14)
		(diameter 0)
		(color 0 0 0 0)
	)
	(junction
		(at 177.8 170.18)
		(diameter 0)
		(color 0 0 0 0)
	)
	(junction
		(at 81.28 129.54)
		(diameter 0)
		(color 0 0 0 0)
	)
	(junction
		(at 165.1 127)
		(diameter 0)
		(color 0 0 0 0)
	)
	(junction
		(at 314.96 96.52)
		(diameter 0)
		(color 0 0 0 0)
	)
	(junction
		(at 168.91 48.26)
		(diameter 0)
		(color 0 0 0 0)
	)
	(junction
		(at 177.8 48.26)
		(diameter 0)
		(color 0 0 0 0)
	)
	(junction
		(at 160.02 48.26)
		(diameter 0)
		(color 0 0 0 0)
	)
	(junction
		(at 110.49 129.54)
		(diameter 0)
		(color 0 0 0 0)
	)
	(no_connect
		(at 279.4 246.38)
	)
	(no_connect
		(at 279.4 193.04)
	)
	(no_connect
		(at 279.4 180.34)
	)
	(no_connect
		(at 279.4 241.3)
	)
	(no_connect
		(at 223.52 182.88)
	)
	(no_connect
		(at 279.4 205.74)
	)
	(no_connect
		(at 274.32 91.44)
	)
	(no_connect
		(at 279.4 182.88)
	)
	(no_connect
		(at 223.52 190.5)
	)
	(no_connect
		(at 279.4 203.2)
	)
	(no_connect
		(at 279.4 175.26)
	)
	(no_connect
		(at 279.4 190.5)
	)
	(no_connect
		(at 279.4 243.84)
	)
	(no_connect
		(at 223.52 187.96)
	)
	(no_connect
		(at 223.52 180.34)
	)
	(no_connect
		(at 223.52 208.28)
	)
	(no_connect
		(at 279.4 208.28)
	)
	(no_connect
		(at 223.52 213.36)
	)
	(no_connect
		(at 279.4 238.76)
	)
	(no_connect
		(at 279.4 177.8)
	)
	(no_connect
		(at 279.4 254)
	)
	(no_connect
		(at 223.52 205.74)
	)
	(no_connect
		(at 274.32 83.82)
	)
	(no_connect
		(at 279.4 195.58)
	)
	(no_connect
		(at 279.4 233.68)
	)
	(no_connect
		(at 279.4 251.46)
	)
	(no_connect
		(at 279.4 236.22)
	)
	(no_connect
		(at 279.4 200.66)
	)
	(no_connect
		(at 223.52 210.82)
	)
	(no_connect
		(at 279.4 187.96)
	)
	(no_connect
		(at 274.32 88.9)
	)
	(no_connect
		(at 279.4 231.14)
	)
	(no_connect
		(at 279.4 248.92)
	)
	(bus_entry
		(at 345.44 129.54)
		(size -2.54 -2.54)
		(stroke
			(width 0)
			(type default)
		)
	)
	(bus_entry
		(at 82.55 198.12)
		(size 2.54 -2.54)
		(stroke
			(width 0)
			(type default)
		)
	)
	(bus_entry
		(at 345.44 132.08)
		(size -2.54 -2.54)
		(stroke
			(width 0)
			(type default)
		)
	)
	(bus_entry
		(at 345.44 127)
		(size -2.54 -2.54)
		(stroke
			(width 0)
			(type default)
		)
	)
	(bus_entry
		(at 82.55 200.66)
		(size 2.54 -2.54)
		(stroke
			(width 0)
			(type default)
		)
	)
	(bus_entry
		(at 345.44 124.46)
		(size -2.54 -2.54)
		(stroke
			(width 0)
			(type default)
		)
	)
	(wire
		(pts
			(xy 213.36 71.12) (xy 213.36 96.52)
		)
		(stroke
			(width 0)
			(type default)
		)
	)
	(wire
		(pts
			(xy 165.1 127) (xy 165.1 132.08)
		)
		(stroke
			(width 0)
			(type default)
		)
	)
	(wire
		(pts
			(xy 93.98 237.49) (xy 110.49 237.49)
		)
		(stroke
			(width 0)
			(type default)
		)
	)
	(wire
		(pts
			(xy 308.61 204.47) (xy 308.61 207.01)
		)
		(stroke
			(width 0)
			(type default)
		)
	)
	(wire
		(pts
			(xy 306.07 111.76) (xy 322.58 111.76)
		)
		(stroke
			(width 0)
			(type default)
		)
	)
	(wire
		(pts
			(xy 314.96 137.16) (xy 314.96 139.7)
		)
		(stroke
			(width 0)
			(type default)
		)
	)
	(wire
		(pts
			(xy 93.98 228.6) (xy 93.98 237.49)
		)
		(stroke
			(width 0)
			(type default)
		)
	)
	(bus
		(pts
			(xy 82.55 200.66) (xy 82.55 203.2)
		)
		(stroke
			(width 0)
			(type default)
		)
	)
	(wire
		(pts
			(xy 168.91 50.8) (xy 168.91 48.26)
		)
		(stroke
			(width 0)
			(type default)
		)
	)
	(wire
		(pts
			(xy 274.32 93.98) (xy 303.53 93.98)
		)
		(stroke
			(width 0)
			(type default)
		)
	)
	(wire
		(pts
			(xy 181.61 226.06) (xy 223.52 226.06)
		)
		(stroke
			(width 0)
			(type default)
		)
	)
	(wire
		(pts
			(xy 314.96 99.06) (xy 314.96 96.52)
		)
		(stroke
			(width 0)
			(type default)
		)
	)
	(wire
		(pts
			(xy 288.29 106.68) (xy 288.29 104.14)
		)
		(stroke
			(width 0)
			(type default)
		)
	)
	(wire
		(pts
			(xy 133.35 179.07) (xy 133.35 193.04)
		)
		(stroke
			(width 0)
			(type default)
		)
	)
	(wire
		(pts
			(xy 176.53 104.14) (xy 167.64 104.14)
		)
		(stroke
			(width 0)
			(type default)
		)
	)
	(wire
		(pts
			(xy 279.4 213.36) (xy 283.21 213.36)
		)
		(stroke
			(width 0)
			(type default)
		)
	)
	(wire
		(pts
			(xy 210.82 241.3) (xy 223.52 241.3)
		)
		(stroke
			(width 0)
			(type default)
		)
	)
	(wire
		(pts
			(xy 146.05 220.98) (xy 146.05 223.52)
		)
		(stroke
			(width 0)
			(type default)
		)
	)
	(wire
		(pts
			(xy 107.95 200.66) (xy 107.95 203.2)
		)
		(stroke
			(width 0)
			(type default)
		)
	)
	(wire
		(pts
			(xy 297.18 96.52) (xy 306.07 96.52)
		)
		(stroke
			(width 0)
			(type default)
		)
	)
	(wire
		(pts
			(xy 130.81 242.57) (xy 133.35 242.57)
		)
		(stroke
			(width 0)
			(type default)
		)
	)
	(wire
		(pts
			(xy 147.32 240.03) (xy 147.32 245.11)
		)
		(stroke
			(width 0)
			(type default)
		)
	)
	(wire
		(pts
			(xy 204.47 187.96) (xy 204.47 185.42)
		)
		(stroke
			(width 0)
			(type default)
		)
	)
	(wire
		(pts
			(xy 283.21 220.98) (xy 283.21 223.52)
		)
		(stroke
			(width 0)
			(type default)
		)
	)
	(wire
		(pts
			(xy 285.75 165.1) (xy 285.75 170.18)
		)
		(stroke
			(width 0)
			(type default)
		)
	)
	(wire
		(pts
			(xy 167.64 127) (xy 228.6 127)
		)
		(stroke
			(width 0)
			(type default)
		)
	)
	(wire
		(pts
			(xy 205.74 78.74) (xy 205.74 106.68)
		)
		(stroke
			(width 0)
			(type default)
		)
	)
	(wire
		(pts
			(xy 139.7 240.03) (xy 130.81 240.03)
		)
		(stroke
			(width 0)
			(type default)
		)
	)
	(wire
		(pts
			(xy 130.81 198.12) (xy 200.66 198.12)
		)
		(stroke
			(width 0)
			(type default)
		)
	)
	(wire
		(pts
			(xy 154.94 223.52) (xy 223.52 223.52)
		)
		(stroke
			(width 0)
			(type default)
		)
	)
	(bus
		(pts
			(xy 82.55 198.12) (xy 82.55 200.66)
		)
		(stroke
			(width 0)
			(type default)
		)
	)
	(wire
		(pts
			(xy 177.8 55.88) (xy 177.8 71.12)
		)
		(stroke
			(width 0)
			(type default)
		)
	)
	(wire
		(pts
			(xy 181.61 226.06) (xy 181.61 254)
		)
		(stroke
			(width 0)
			(type default)
		)
	)
	(wire
		(pts
			(xy 133.35 73.66) (xy 168.91 73.66)
		)
		(stroke
			(width 0)
			(type default)
		)
	)
	(wire
		(pts
			(xy 283.21 223.52) (xy 283.21 226.06)
		)
		(stroke
			(width 0)
			(type default)
		)
	)
	(wire
		(pts
			(xy 133.35 60.96) (xy 186.69 60.96)
		)
		(stroke
			(width 0)
			(type default)
		)
	)
	(wire
		(pts
			(xy 274.32 129.54) (xy 342.9 129.54)
		)
		(stroke
			(width 0)
			(type default)
		)
	)
	(wire
		(pts
			(xy 168.91 55.88) (xy 168.91 73.66)
		)
		(stroke
			(width 0)
			(type default)
		)
	)
	(wire
		(pts
			(xy 177.8 50.8) (xy 177.8 48.26)
		)
		(stroke
			(width 0)
			(type default)
		)
	)
	(wire
		(pts
			(xy 213.36 193.04) (xy 213.36 200.66)
		)
		(stroke
			(width 0)
			(type default)
		)
	)
	(wire
		(pts
			(xy 138.43 179.07) (xy 133.35 179.07)
		)
		(stroke
			(width 0)
			(type default)
		)
	)
	(wire
		(pts
			(xy 133.35 71.12) (xy 177.8 71.12)
		)
		(stroke
			(width 0)
			(type default)
		)
	)
	(wire
		(pts
			(xy 281.94 157.48) (xy 281.94 160.02)
		)
		(stroke
			(width 0)
			(type default)
		)
	)
	(wire
		(pts
			(xy 274.32 109.22) (xy 297.18 109.22)
		)
		(stroke
			(width 0)
			(type default)
		)
	)
	(wire
		(pts
			(xy 186.69 50.8) (xy 186.69 48.26)
		)
		(stroke
			(width 0)
			(type default)
		)
	)
	(wire
		(pts
			(xy 73.66 121.92) (xy 73.66 119.38)
		)
		(stroke
			(width 0)
			(type default)
		)
	)
	(wire
		(pts
			(xy 176.53 124.46) (xy 228.6 124.46)
		)
		(stroke
			(width 0)
			(type default)
		)
	)
	(wire
		(pts
			(xy 151.13 78.74) (xy 194.31 78.74)
		)
		(stroke
			(width 0)
			(type default)
		)
	)
	(wire
		(pts
			(xy 144.78 240.03) (xy 147.32 240.03)
		)
		(stroke
			(width 0)
			(type default)
		)
	)
	(bus
		(pts
			(xy 80.01 205.74) (xy 82.55 203.2)
		)
		(stroke
			(width 0)
			(type default)
		)
	)
	(wire
		(pts
			(xy 314.96 124.46) (xy 342.9 124.46)
		)
		(stroke
			(width 0)
			(type default)
		)
	)
	(wire
		(pts
			(xy 146.05 228.6) (xy 146.05 237.49)
		)
		(stroke
			(width 0)
			(type default)
		)
	)
	(bus
		(pts
			(xy 347.98 137.16) (xy 345.44 134.62)
		)
		(stroke
			(width 0)
			(type default)
		)
	)
	(wire
		(pts
			(xy 85.09 198.12) (xy 110.49 198.12)
		)
		(stroke
			(width 0)
			(type default)
		)
	)
	(wire
		(pts
			(xy 171.45 86.36) (xy 171.45 88.9)
		)
		(stroke
			(width 0)
			(type default)
		)
	)
	(wire
		(pts
			(xy 226.06 58.42) (xy 189.23 58.42)
		)
		(stroke
			(width 0)
			(type default)
		)
	)
	(wire
		(pts
			(xy 85.09 195.58) (xy 110.49 195.58)
		)
		(stroke
			(width 0)
			(type default)
		)
	)
	(wire
		(pts
			(xy 66.04 129.54) (xy 71.12 129.54)
		)
		(stroke
			(width 0)
			(type default)
		)
	)
	(wire
		(pts
			(xy 177.8 48.26) (xy 186.69 48.26)
		)
		(stroke
			(width 0)
			(type default)
		)
	)
	(wire
		(pts
			(xy 110.49 139.7) (xy 110.49 129.54)
		)
		(stroke
			(width 0)
			(type default)
		)
	)
	(bus
		(pts
			(xy 345.44 124.46) (xy 345.44 127)
		)
		(stroke
			(width 0)
			(type default)
		)
	)
	(wire
		(pts
			(xy 163.83 215.9) (xy 223.52 215.9)
		)
		(stroke
			(width 0)
			(type default)
		)
	)
	(wire
		(pts
			(xy 133.35 76.2) (xy 160.02 76.2)
		)
		(stroke
			(width 0)
			(type default)
		)
	)
	(wire
		(pts
			(xy 297.18 96.52) (xy 297.18 99.06)
		)
		(stroke
			(width 0)
			(type default)
		)
	)
	(wire
		(pts
			(xy 107.95 176.53) (xy 107.95 179.07)
		)
		(stroke
			(width 0)
			(type default)
		)
	)
	(wire
		(pts
			(xy 213.36 96.52) (xy 228.6 96.52)
		)
		(stroke
			(width 0)
			(type default)
		)
	)
	(wire
		(pts
			(xy 158.75 129.54) (xy 228.6 129.54)
		)
		(stroke
			(width 0)
			(type default)
		)
	)
	(wire
		(pts
			(xy 186.69 106.68) (xy 186.69 104.14)
		)
		(stroke
			(width 0)
			(type default)
		)
	)
	(wire
		(pts
			(xy 172.72 218.44) (xy 223.52 218.44)
		)
		(stroke
			(width 0)
			(type default)
		)
	)
	(bus
		(pts
			(xy 77.47 205.74) (xy 80.01 205.74)
		)
		(stroke
			(width 0)
			(type default)
		)
	)
	(wire
		(pts
			(xy 154.94 137.16) (xy 154.94 139.7)
		)
		(stroke
			(width 0)
			(type default)
		)
	)
	(wire
		(pts
			(xy 279.4 218.44) (xy 283.21 218.44)
		)
		(stroke
			(width 0)
			(type default)
		)
	)
	(wire
		(pts
			(xy 165.1 127) (xy 167.64 127)
		)
		(stroke
			(width 0)
			(type default)
		)
	)
	(wire
		(pts
			(xy 218.44 88.9) (xy 228.6 88.9)
		)
		(stroke
			(width 0)
			(type default)
		)
	)
	(wire
		(pts
			(xy 200.66 185.42) (xy 204.47 185.42)
		)
		(stroke
			(width 0)
			(type default)
		)
	)
	(wire
		(pts
			(xy 274.32 124.46) (xy 294.64 124.46)
		)
		(stroke
			(width 0)
			(type default)
		)
	)
	(wire
		(pts
			(xy 189.23 86.36) (xy 189.23 88.9)
		)
		(stroke
			(width 0)
			(type default)
		)
	)
	(wire
		(pts
			(xy 137.16 220.98) (xy 146.05 220.98)
		)
		(stroke
			(width 0)
			(type default)
		)
	)
	(wire
		(pts
			(xy 160.02 48.26) (xy 168.91 48.26)
		)
		(stroke
			(width 0)
			(type default)
		)
	)
	(bus
		(pts
			(xy 345.44 127) (xy 345.44 129.54)
		)
		(stroke
			(width 0)
			(type default)
		)
	)
	(wire
		(pts
			(xy 274.32 121.92) (xy 314.96 121.92)
		)
		(stroke
			(width 0)
			(type default)
		)
	)
	(wire
		(pts
			(xy 172.72 251.46) (xy 172.72 254)
		)
		(stroke
			(width 0)
			(type default)
		)
	)
	(wire
		(pts
			(xy 81.28 129.54) (xy 85.09 129.54)
		)
		(stroke
			(width 0)
			(type default)
		)
	)
	(wire
		(pts
			(xy 205.74 106.68) (xy 228.6 106.68)
		)
		(stroke
			(width 0)
			(type default)
		)
	)
	(wire
		(pts
			(xy 158.75 106.68) (xy 158.75 104.14)
		)
		(stroke
			(width 0)
			(type default)
		)
	)
	(wire
		(pts
			(xy 220.98 63.5) (xy 220.98 86.36)
		)
		(stroke
			(width 0)
			(type default)
		)
	)
	(wire
		(pts
			(xy 133.35 66.04) (xy 171.45 66.04)
		)
		(stroke
			(width 0)
			(type default)
		)
	)
	(wire
		(pts
			(xy 190.5 231.14) (xy 190.5 246.38)
		)
		(stroke
			(width 0)
			(type default)
		)
	)
	(wire
		(pts
			(xy 91.44 237.49) (xy 93.98 237.49)
		)
		(stroke
			(width 0)
			(type default)
		)
	)
	(wire
		(pts
			(xy 107.95 220.98) (xy 102.87 220.98)
		)
		(stroke
			(width 0)
			(type default)
		)
	)
	(wire
		(pts
			(xy 107.95 193.04) (xy 110.49 193.04)
		)
		(stroke
			(width 0)
			(type default)
		)
	)
	(wire
		(pts
			(xy 168.91 167.64) (xy 191.77 167.64)
		)
		(stroke
			(width 0)
			(type default)
		)
	)
	(wire
		(pts
			(xy 186.69 116.84) (xy 228.6 116.84)
		)
		(stroke
			(width 0)
			(type default)
		)
	)
	(wire
		(pts
			(xy 96.52 139.7) (xy 110.49 139.7)
		)
		(stroke
			(width 0)
			(type default)
		)
	)
	(wire
		(pts
			(xy 281.94 165.1) (xy 281.94 167.64)
		)
		(stroke
			(width 0)
			(type default)
		)
	)
	(wire
		(pts
			(xy 151.13 127) (xy 154.94 127)
		)
		(stroke
			(width 0)
			(type default)
		)
	)
	(wire
		(pts
			(xy 138.43 179.07) (xy 138.43 176.53)
		)
		(stroke
			(width 0)
			(type default)
		)
	)
	(wire
		(pts
			(xy 102.87 129.54) (xy 110.49 129.54)
		)
		(stroke
			(width 0)
			(type default)
		)
	)
	(wire
		(pts
			(xy 314.96 124.46) (xy 314.96 132.08)
		)
		(stroke
			(width 0)
			(type default)
		)
	)
	(wire
		(pts
			(xy 99.06 240.03) (xy 96.52 240.03)
		)
		(stroke
			(width 0)
			(type default)
		)
	)
	(wire
		(pts
			(xy 208.28 104.14) (xy 228.6 104.14)
		)
		(stroke
			(width 0)
			(type default)
		)
	)
	(wire
		(pts
			(xy 223.52 60.96) (xy 223.52 83.82)
		)
		(stroke
			(width 0)
			(type default)
		)
	)
	(wire
		(pts
			(xy 274.32 111.76) (xy 306.07 111.76)
		)
		(stroke
			(width 0)
			(type default)
		)
	)
	(wire
		(pts
			(xy 210.82 99.06) (xy 228.6 99.06)
		)
		(stroke
			(width 0)
			(type default)
		)
	)
	(wire
		(pts
			(xy 314.96 121.92) (xy 342.9 121.92)
		)
		(stroke
			(width 0)
			(type default)
		)
	)
	(wire
		(pts
			(xy 285.75 154.94) (xy 285.75 157.48)
		)
		(stroke
			(width 0)
			(type default)
		)
	)
	(wire
		(pts
			(xy 176.53 104.14) (xy 186.69 104.14)
		)
		(stroke
			(width 0)
			(type default)
		)
	)
	(wire
		(pts
			(xy 151.13 48.26) (xy 151.13 50.8)
		)
		(stroke
			(width 0)
			(type default)
		)
	)
	(wire
		(pts
			(xy 151.13 55.88) (xy 151.13 78.74)
		)
		(stroke
			(width 0)
			(type default)
		)
	)
	(wire
		(pts
			(xy 137.16 228.6) (xy 137.16 231.14)
		)
		(stroke
			(width 0)
			(type default)
		)
	)
	(wire
		(pts
			(xy 110.49 242.57) (xy 107.95 242.57)
		)
		(stroke
			(width 0)
			(type default)
		)
	)
	(wire
		(pts
			(xy 297.18 109.22) (xy 322.58 109.22)
		)
		(stroke
			(width 0)
			(type default)
		)
	)
	(wire
		(pts
			(xy 285.75 157.48) (xy 281.94 157.48)
		)
		(stroke
			(width 0)
			(type default)
		)
	)
	(wire
		(pts
			(xy 133.35 78.74) (xy 151.13 78.74)
		)
		(stroke
			(width 0)
			(type default)
		)
	)
	(wire
		(pts
			(xy 93.98 223.52) (xy 93.98 220.98)
		)
		(stroke
			(width 0)
			(type default)
		)
	)
	(wire
		(pts
			(xy 177.8 71.12) (xy 213.36 71.12)
		)
		(stroke
			(width 0)
			(type default)
		)
	)
	(wire
		(pts
			(xy 138.43 186.69) (xy 138.43 189.23)
		)
		(stroke
			(width 0)
			(type default)
		)
	)
	(wire
		(pts
			(xy 208.28 76.2) (xy 208.28 104.14)
		)
		(stroke
			(width 0)
			(type default)
		)
	)
	(wire
		(pts
			(xy 158.75 104.14) (xy 167.64 104.14)
		)
		(stroke
			(width 0)
			(type default)
		)
	)
	(wire
		(pts
			(xy 274.32 86.36) (xy 278.13 86.36)
		)
		(stroke
			(width 0)
			(type default)
		)
	)
	(wire
		(pts
			(xy 279.4 215.9) (xy 308.61 215.9)
		)
		(stroke
			(width 0)
			(type default)
		)
	)
	(bus
		(pts
			(xy 345.44 129.54) (xy 345.44 132.08)
		)
		(stroke
			(width 0)
			(type default)
		)
	)
	(wire
		(pts
			(xy 226.06 81.28) (xy 228.6 81.28)
		)
		(stroke
			(width 0)
			(type default)
		)
	)
	(wire
		(pts
			(xy 154.94 223.52) (xy 154.94 237.49)
		)
		(stroke
			(width 0)
			(type default)
		)
	)
	(wire
		(pts
			(xy 274.32 127) (xy 342.9 127)
		)
		(stroke
			(width 0)
			(type default)
		)
	)
	(wire
		(pts
			(xy 76.2 129.54) (xy 81.28 129.54)
		)
		(stroke
			(width 0)
			(type default)
		)
	)
	(wire
		(pts
			(xy 171.45 66.04) (xy 194.31 66.04)
		)
		(stroke
			(width 0)
			(type default)
		)
	)
	(wire
		(pts
			(xy 210.82 238.76) (xy 223.52 238.76)
		)
		(stroke
			(width 0)
			(type default)
		)
	)
	(wire
		(pts
			(xy 220.98 86.36) (xy 228.6 86.36)
		)
		(stroke
			(width 0)
			(type default)
		)
	)
	(wire
		(pts
			(xy 110.49 129.54) (xy 158.75 129.54)
		)
		(stroke
			(width 0)
			(type default)
		)
	)
	(wire
		(pts
			(xy 151.13 45.72) (xy 151.13 48.26)
		)
		(stroke
			(width 0)
			(type default)
		)
	)
	(wire
		(pts
			(xy 151.13 104.14) (xy 151.13 106.68)
		)
		(stroke
			(width 0)
			(type default)
		)
	)
	(wire
		(pts
			(xy 176.53 137.16) (xy 176.53 139.7)
		)
		(stroke
			(width 0)
			(type default)
		)
	)
	(wire
		(pts
			(xy 274.32 81.28) (xy 278.13 81.28)
		)
		(stroke
			(width 0)
			(type default)
		)
	)
	(wire
		(pts
			(xy 133.35 58.42) (xy 189.23 58.42)
		)
		(stroke
			(width 0)
			(type default)
		)
	)
	(wire
		(pts
			(xy 314.96 93.98) (xy 314.96 96.52)
		)
		(stroke
			(width 0)
			(type default)
		)
	)
	(wire
		(pts
			(xy 314.96 104.14) (xy 314.96 121.92)
		)
		(stroke
			(width 0)
			(type default)
		)
	)
	(wire
		(pts
			(xy 171.45 81.28) (xy 171.45 66.04)
		)
		(stroke
			(width 0)
			(type default)
		)
	)
	(wire
		(pts
			(xy 165.1 137.16) (xy 165.1 139.7)
		)
		(stroke
			(width 0)
			(type default)
		)
	)
	(bus
		(pts
			(xy 345.44 132.08) (xy 345.44 134.62)
		)
		(stroke
			(width 0)
			(type default)
		)
	)
	(wire
		(pts
			(xy 151.13 111.76) (xy 151.13 121.92)
		)
		(stroke
			(width 0)
			(type default)
		)
	)
	(wire
		(pts
			(xy 168.91 73.66) (xy 194.31 73.66)
		)
		(stroke
			(width 0)
			(type default)
		)
	)
	(wire
		(pts
			(xy 195.58 114.3) (xy 228.6 114.3)
		)
		(stroke
			(width 0)
			(type default)
		)
	)
	(wire
		(pts
			(xy 153.67 170.18) (xy 153.67 166.37)
		)
		(stroke
			(width 0)
			(type default)
		)
	)
	(wire
		(pts
			(xy 213.36 182.88) (xy 213.36 185.42)
		)
		(stroke
			(width 0)
			(type default)
		)
	)
	(wire
		(pts
			(xy 306.07 104.14) (xy 306.07 111.76)
		)
		(stroke
			(width 0)
			(type default)
		)
	)
	(wire
		(pts
			(xy 110.49 240.03) (xy 104.14 240.03)
		)
		(stroke
			(width 0)
			(type default)
		)
	)
	(wire
		(pts
			(xy 102.87 186.69) (xy 102.87 189.23)
		)
		(stroke
			(width 0)
			(type default)
		)
	)
	(wire
		(pts
			(xy 200.66 198.12) (xy 223.52 198.12)
		)
		(stroke
			(width 0)
			(type default)
		)
	)
	(wire
		(pts
			(xy 107.95 179.07) (xy 102.87 179.07)
		)
		(stroke
			(width 0)
			(type default)
		)
	)
	(wire
		(pts
			(xy 105.41 132.08) (xy 102.87 132.08)
		)
		(stroke
			(width 0)
			(type default)
		)
	)
	(wire
		(pts
			(xy 281.94 167.64) (xy 279.4 167.64)
		)
		(stroke
			(width 0)
			(type default)
		)
	)
	(wire
		(pts
			(xy 283.21 213.36) (xy 283.21 218.44)
		)
		(stroke
			(width 0)
			(type default)
		)
	)
	(wire
		(pts
			(xy 81.28 139.7) (xy 81.28 129.54)
		)
		(stroke
			(width 0)
			(type default)
		)
	)
	(wire
		(pts
			(xy 91.44 139.7) (xy 81.28 139.7)
		)
		(stroke
			(width 0)
			(type default)
		)
	)
	(wire
		(pts
			(xy 208.28 175.26) (xy 223.52 175.26)
		)
		(stroke
			(width 0)
			(type default)
		)
	)
	(wire
		(pts
			(xy 199.39 73.66) (xy 210.82 73.66)
		)
		(stroke
			(width 0)
			(type default)
		)
	)
	(wire
		(pts
			(xy 283.21 226.06) (xy 283.21 254)
		)
		(stroke
			(width 0)
			(type default)
		)
	)
	(wire
		(pts
			(xy 154.94 127) (xy 154.94 132.08)
		)
		(stroke
			(width 0)
			(type default)
		)
	)
	(wire
		(pts
			(xy 154.94 127) (xy 165.1 127)
		)
		(stroke
			(width 0)
			(type default)
		)
	)
	(wire
		(pts
			(xy 199.39 78.74) (xy 205.74 78.74)
		)
		(stroke
			(width 0)
			(type default)
		)
	)
	(wire
		(pts
			(xy 172.72 218.44) (xy 172.72 246.38)
		)
		(stroke
			(width 0)
			(type default)
		)
	)
	(wire
		(pts
			(xy 274.32 106.68) (xy 288.29 106.68)
		)
		(stroke
			(width 0)
			(type default)
		)
	)
	(wire
		(pts
			(xy 176.53 124.46) (xy 176.53 111.76)
		)
		(stroke
			(width 0)
			(type default)
		)
	)
	(wire
		(pts
			(xy 168.91 166.37) (xy 168.91 167.64)
		)
		(stroke
			(width 0)
			(type default)
		)
	)
	(wire
		(pts
			(xy 204.47 193.04) (xy 204.47 195.58)
		)
		(stroke
			(width 0)
			(type default)
		)
	)
	(wire
		(pts
			(xy 204.47 185.42) (xy 213.36 185.42)
		)
		(stroke
			(width 0)
			(type default)
		)
	)
	(wire
		(pts
			(xy 133.35 234.95) (xy 130.81 234.95)
		)
		(stroke
			(width 0)
			(type default)
		)
	)
	(wire
		(pts
			(xy 107.95 179.07) (xy 107.95 193.04)
		)
		(stroke
			(width 0)
			(type default)
		)
	)
	(wire
		(pts
			(xy 195.58 114.3) (xy 195.58 132.08)
		)
		(stroke
			(width 0)
			(type default)
		)
	)
	(wire
		(pts
			(xy 285.75 170.18) (xy 288.29 170.18)
		)
		(stroke
			(width 0)
			(type default)
		)
	)
	(wire
		(pts
			(xy 96.52 240.03) (xy 96.52 245.11)
		)
		(stroke
			(width 0)
			(type default)
		)
	)
	(wire
		(pts
			(xy 189.23 58.42) (xy 189.23 81.28)
		)
		(stroke
			(width 0)
			(type default)
		)
	)
	(wire
		(pts
			(xy 196.85 170.18) (xy 223.52 170.18)
		)
		(stroke
			(width 0)
			(type default)
		)
	)
	(wire
		(pts
			(xy 223.52 60.96) (xy 199.39 60.96)
		)
		(stroke
			(width 0)
			(type default)
		)
	)
	(wire
		(pts
			(xy 186.69 111.76) (xy 186.69 116.84)
		)
		(stroke
			(width 0)
			(type default)
		)
	)
	(wire
		(pts
			(xy 285.75 157.48) (xy 285.75 160.02)
		)
		(stroke
			(width 0)
			(type default)
		)
	)
	(wire
		(pts
			(xy 199.39 243.84) (xy 199.39 254)
		)
		(stroke
			(width 0)
			(type default)
		)
	)
	(wire
		(pts
			(xy 102.87 228.6) (xy 102.87 231.14)
		)
		(stroke
			(width 0)
			(type default)
		)
	)
	(wire
		(pts
			(xy 133.35 193.04) (xy 130.81 193.04)
		)
		(stroke
			(width 0)
			(type default)
		)
	)
	(wire
		(pts
			(xy 288.29 96.52) (xy 297.18 96.52)
		)
		(stroke
			(width 0)
			(type default)
		)
	)
	(wire
		(pts
			(xy 153.67 166.37) (xy 168.91 166.37)
		)
		(stroke
			(width 0)
			(type default)
		)
	)
	(wire
		(pts
			(xy 215.9 68.58) (xy 162.56 68.58)
		)
		(stroke
			(width 0)
			(type default)
		)
	)
	(wire
		(pts
			(xy 195.58 104.14) (xy 186.69 104.14)
		)
		(stroke
			(width 0)
			(type default)
		)
	)
	(wire
		(pts
			(xy 168.91 48.26) (xy 177.8 48.26)
		)
		(stroke
			(width 0)
			(type default)
		)
	)
	(wire
		(pts
			(xy 151.13 101.6) (xy 151.13 104.14)
		)
		(stroke
			(width 0)
			(type default)
		)
	)
	(wire
		(pts
			(xy 107.95 242.57) (xy 107.95 245.11)
		)
		(stroke
			(width 0)
			(type default)
		)
	)
	(wire
		(pts
			(xy 195.58 137.16) (xy 195.58 139.7)
		)
		(stroke
			(width 0)
			(type default)
		)
	)
	(wire
		(pts
			(xy 200.66 193.04) (xy 200.66 198.12)
		)
		(stroke
			(width 0)
			(type default)
		)
	)
	(wire
		(pts
			(xy 93.98 220.98) (xy 102.87 220.98)
		)
		(stroke
			(width 0)
			(type default)
		)
	)
	(wire
		(pts
			(xy 190.5 251.46) (xy 190.5 254)
		)
		(stroke
			(width 0)
			(type default)
		)
	)
	(wire
		(pts
			(xy 130.81 200.66) (xy 133.35 200.66)
		)
		(stroke
			(width 0)
			(type default)
		)
	)
	(wire
		(pts
			(xy 195.58 111.76) (xy 195.58 114.3)
		)
		(stroke
			(width 0)
			(type default)
		)
	)
	(wire
		(pts
			(xy 130.81 195.58) (xy 204.47 195.58)
		)
		(stroke
			(width 0)
			(type default)
		)
	)
	(wire
		(pts
			(xy 163.83 215.9) (xy 163.83 254)
		)
		(stroke
			(width 0)
			(type default)
		)
	)
	(wire
		(pts
			(xy 186.69 137.16) (xy 186.69 139.7)
		)
		(stroke
			(width 0)
			(type default)
		)
	)
	(wire
		(pts
			(xy 194.31 60.96) (xy 186.69 60.96)
		)
		(stroke
			(width 0)
			(type default)
		)
	)
	(wire
		(pts
			(xy 279.4 226.06) (xy 283.21 226.06)
		)
		(stroke
			(width 0)
			(type default)
		)
	)
	(wire
		(pts
			(xy 133.35 220.98) (xy 137.16 220.98)
		)
		(stroke
			(width 0)
			(type default)
		)
	)
	(wire
		(pts
			(xy 107.95 234.95) (xy 110.49 234.95)
		)
		(stroke
			(width 0)
			(type default)
		)
	)
	(wire
		(pts
			(xy 297.18 104.14) (xy 297.18 109.22)
		)
		(stroke
			(width 0)
			(type default)
		)
	)
	(wire
		(pts
			(xy 102.87 179.07) (xy 102.87 181.61)
		)
		(stroke
			(width 0)
			(type default)
		)
	)
	(wire
		(pts
			(xy 190.5 231.14) (xy 223.52 231.14)
		)
		(stroke
			(width 0)
			(type default)
		)
	)
	(wire
		(pts
			(xy 158.75 129.54) (xy 158.75 111.76)
		)
		(stroke
			(width 0)
			(type default)
		)
	)
	(wire
		(pts
			(xy 177.8 180.34) (xy 177.8 182.88)
		)
		(stroke
			(width 0)
			(type default)
		)
	)
	(wire
		(pts
			(xy 176.53 106.68) (xy 176.53 104.14)
		)
		(stroke
			(width 0)
			(type default)
		)
	)
	(wire
		(pts
			(xy 160.02 55.88) (xy 160.02 76.2)
		)
		(stroke
			(width 0)
			(type default)
		)
	)
	(wire
		(pts
			(xy 213.36 200.66) (xy 223.52 200.66)
		)
		(stroke
			(width 0)
			(type default)
		)
	)
	(wire
		(pts
			(xy 107.95 220.98) (xy 107.95 234.95)
		)
		(stroke
			(width 0)
			(type default)
		)
	)
	(wire
		(pts
			(xy 210.82 233.68) (xy 223.52 233.68)
		)
		(stroke
			(width 0)
			(type default)
		)
	)
	(wire
		(pts
			(xy 210.82 236.22) (xy 223.52 236.22)
		)
		(stroke
			(width 0)
			(type default)
		)
	)
	(wire
		(pts
			(xy 279.4 223.52) (xy 283.21 223.52)
		)
		(stroke
			(width 0)
			(type default)
		)
	)
	(wire
		(pts
			(xy 210.82 73.66) (xy 210.82 99.06)
		)
		(stroke
			(width 0)
			(type default)
		)
	)
	(wire
		(pts
			(xy 133.35 68.58) (xy 162.56 68.58)
		)
		(stroke
			(width 0)
			(type default)
		)
	)
	(wire
		(pts
			(xy 107.95 218.44) (xy 107.95 220.98)
		)
		(stroke
			(width 0)
			(type default)
		)
	)
	(wire
		(pts
			(xy 168.91 167.64) (xy 168.91 175.26)
		)
		(stroke
			(width 0)
			(type default)
		)
	)
	(wire
		(pts
			(xy 151.13 121.92) (xy 228.6 121.92)
		)
		(stroke
			(width 0)
			(type default)
		)
	)
	(wire
		(pts
			(xy 223.52 83.82) (xy 228.6 83.82)
		)
		(stroke
			(width 0)
			(type default)
		)
	)
	(wire
		(pts
			(xy 186.69 116.84) (xy 186.69 132.08)
		)
		(stroke
			(width 0)
			(type default)
		)
	)
	(wire
		(pts
			(xy 160.02 175.26) (xy 160.02 182.88)
		)
		(stroke
			(width 0)
			(type default)
		)
	)
	(wire
		(pts
			(xy 180.34 81.28) (xy 180.34 63.5)
		)
		(stroke
			(width 0)
			(type default)
		)
	)
	(wire
		(pts
			(xy 102.87 220.98) (xy 102.87 223.52)
		)
		(stroke
			(width 0)
			(type default)
		)
	)
	(wire
		(pts
			(xy 73.66 111.76) (xy 82.55 111.76)
		)
		(stroke
			(width 0)
			(type default)
		)
	)
	(wire
		(pts
			(xy 133.35 193.04) (xy 133.35 200.66)
		)
		(stroke
			(width 0)
			(type default)
		)
	)
	(wire
		(pts
			(xy 85.09 125.73) (xy 82.55 125.73)
		)
		(stroke
			(width 0)
			(type default)
		)
	)
	(wire
		(pts
			(xy 285.75 170.18) (xy 279.4 170.18)
		)
		(stroke
			(width 0)
			(type default)
		)
	)
	(wire
		(pts
			(xy 218.44 66.04) (xy 199.39 66.04)
		)
		(stroke
			(width 0)
			(type default)
		)
	)
	(wire
		(pts
			(xy 215.9 91.44) (xy 228.6 91.44)
		)
		(stroke
			(width 0)
			(type default)
		)
	)
	(wire
		(pts
			(xy 308.61 212.09) (xy 308.61 215.9)
		)
		(stroke
			(width 0)
			(type default)
		)
	)
	(wire
		(pts
			(xy 299.72 124.46) (xy 314.96 124.46)
		)
		(stroke
			(width 0)
			(type default)
		)
	)
	(wire
		(pts
			(xy 189.23 175.26) (xy 189.23 172.72)
		)
		(stroke
			(width 0)
			(type default)
		)
	)
	(wire
		(pts
			(xy 195.58 106.68) (xy 195.58 104.14)
		)
		(stroke
			(width 0)
			(type default)
		)
	)
	(wire
		(pts
			(xy 306.07 96.52) (xy 306.07 99.06)
		)
		(stroke
			(width 0)
			(type default)
		)
	)
	(wire
		(pts
			(xy 113.03 127) (xy 146.05 127)
		)
		(stroke
			(width 0)
			(type default)
		)
	)
	(wire
		(pts
			(xy 226.06 58.42) (xy 226.06 81.28)
		)
		(stroke
			(width 0)
			(type default)
		)
	)
	(wire
		(pts
			(xy 151.13 104.14) (xy 158.75 104.14)
		)
		(stroke
			(width 0)
			(type default)
		)
	)
	(wire
		(pts
			(xy 73.66 114.3) (xy 73.66 111.76)
		)
		(stroke
			(width 0)
			(type default)
		)
	)
	(wire
		(pts
			(xy 160.02 50.8) (xy 160.02 48.26)
		)
		(stroke
			(width 0)
			(type default)
		)
	)
	(wire
		(pts
			(xy 151.13 48.26) (xy 160.02 48.26)
		)
		(stroke
			(width 0)
			(type default)
		)
	)
	(wire
		(pts
			(xy 213.36 185.42) (xy 213.36 187.96)
		)
		(stroke
			(width 0)
			(type default)
		)
	)
	(wire
		(pts
			(xy 162.56 86.36) (xy 162.56 88.9)
		)
		(stroke
			(width 0)
			(type default)
		)
	)
	(wire
		(pts
			(xy 180.34 86.36) (xy 180.34 88.9)
		)
		(stroke
			(width 0)
			(type default)
		)
	)
	(wire
		(pts
			(xy 162.56 68.58) (xy 162.56 81.28)
		)
		(stroke
			(width 0)
			(type default)
		)
	)
	(wire
		(pts
			(xy 180.34 63.5) (xy 220.98 63.5)
		)
		(stroke
			(width 0)
			(type default)
		)
	)
	(wire
		(pts
			(xy 189.23 172.72) (xy 223.52 172.72)
		)
		(stroke
			(width 0)
			(type default)
		)
	)
	(wire
		(pts
			(xy 177.8 170.18) (xy 177.8 175.26)
		)
		(stroke
			(width 0)
			(type default)
		)
	)
	(wire
		(pts
			(xy 177.8 170.18) (xy 191.77 170.18)
		)
		(stroke
			(width 0)
			(type default)
		)
	)
	(wire
		(pts
			(xy 196.85 167.64) (xy 223.52 167.64)
		)
		(stroke
			(width 0)
			(type default)
		)
	)
	(wire
		(pts
			(xy 82.55 125.73) (xy 82.55 111.76)
		)
		(stroke
			(width 0)
			(type default)
		)
	)
	(wire
		(pts
			(xy 146.05 237.49) (xy 130.81 237.49)
		)
		(stroke
			(width 0)
			(type default)
		)
	)
	(wire
		(pts
			(xy 200.66 187.96) (xy 200.66 185.42)
		)
		(stroke
			(width 0)
			(type default)
		)
	)
	(wire
		(pts
			(xy 133.35 218.44) (xy 133.35 220.98)
		)
		(stroke
			(width 0)
			(type default)
		)
	)
	(wire
		(pts
			(xy 160.02 76.2) (xy 208.28 76.2)
		)
		(stroke
			(width 0)
			(type default)
		)
	)
	(wire
		(pts
			(xy 133.35 220.98) (xy 133.35 234.95)
		)
		(stroke
			(width 0)
			(type default)
		)
	)
	(wire
		(pts
			(xy 167.64 111.76) (xy 167.64 127)
		)
		(stroke
			(width 0)
			(type default)
		)
	)
	(wire
		(pts
			(xy 218.44 66.04) (xy 218.44 88.9)
		)
		(stroke
			(width 0)
			(type default)
		)
	)
	(bus
		(pts
			(xy 347.98 137.16) (xy 350.52 137.16)
		)
		(stroke
			(width 0)
			(type default)
		)
	)
	(wire
		(pts
			(xy 105.41 133.35) (xy 105.41 132.08)
		)
		(stroke
			(width 0)
			(type default)
		)
	)
	(wire
		(pts
			(xy 153.67 170.18) (xy 156.21 170.18)
		)
		(stroke
			(width 0)
			(type default)
		)
	)
	(wire
		(pts
			(xy 281.94 167.64) (xy 288.29 167.64)
		)
		(stroke
			(width 0)
			(type default)
		)
	)
	(wire
		(pts
			(xy 283.21 218.44) (xy 283.21 220.98)
		)
		(stroke
			(width 0)
			(type default)
		)
	)
	(wire
		(pts
			(xy 215.9 68.58) (xy 215.9 91.44)
		)
		(stroke
			(width 0)
			(type default)
		)
	)
	(wire
		(pts
			(xy 168.91 180.34) (xy 168.91 182.88)
		)
		(stroke
			(width 0)
			(type default)
		)
	)
	(wire
		(pts
			(xy 110.49 200.66) (xy 107.95 200.66)
		)
		(stroke
			(width 0)
			(type default)
		)
	)
	(wire
		(pts
			(xy 176.53 124.46) (xy 176.53 132.08)
		)
		(stroke
			(width 0)
			(type default)
		)
	)
	(wire
		(pts
			(xy 138.43 179.07) (xy 138.43 181.61)
		)
		(stroke
			(width 0)
			(type default)
		)
	)
	(wire
		(pts
			(xy 167.64 104.14) (xy 167.64 106.68)
		)
		(stroke
			(width 0)
			(type default)
		)
	)
	(wire
		(pts
			(xy 154.94 237.49) (xy 146.05 237.49)
		)
		(stroke
			(width 0)
			(type default)
		)
	)
	(wire
		(pts
			(xy 163.83 170.18) (xy 177.8 170.18)
		)
		(stroke
			(width 0)
			(type default)
		)
	)
	(wire
		(pts
			(xy 199.39 243.84) (xy 223.52 243.84)
		)
		(stroke
			(width 0)
			(type default)
		)
	)
	(wire
		(pts
			(xy 288.29 99.06) (xy 288.29 96.52)
		)
		(stroke
			(width 0)
			(type default)
		)
	)
	(wire
		(pts
			(xy 186.69 55.88) (xy 186.69 60.96)
		)
		(stroke
			(width 0)
			(type default)
		)
	)
	(wire
		(pts
			(xy 279.4 220.98) (xy 283.21 220.98)
		)
		(stroke
			(width 0)
			(type default)
		)
	)
	(wire
		(pts
			(xy 73.66 110.49) (xy 73.66 111.76)
		)
		(stroke
			(width 0)
			(type default)
		)
	)
	(wire
		(pts
			(xy 189.23 180.34) (xy 189.23 182.88)
		)
		(stroke
			(width 0)
			(type default)
		)
	)
	(wire
		(pts
			(xy 137.16 220.98) (xy 137.16 223.52)
		)
		(stroke
			(width 0)
			(type default)
		)
	)
	(wire
		(pts
			(xy 314.96 96.52) (xy 306.07 96.52)
		)
		(stroke
			(width 0)
			(type default)
		)
	)
	(wire
		(pts
			(xy 204.47 195.58) (xy 223.52 195.58)
		)
		(stroke
			(width 0)
			(type default)
		)
	)
	(wire
		(pts
			(xy 133.35 234.95) (xy 133.35 242.57)
		)
		(stroke
			(width 0)
			(type default)
		)
	)
	(wire
		(pts
			(xy 133.35 63.5) (xy 180.34 63.5)
		)
		(stroke
			(width 0)
			(type default)
		)
	)
	(label "XTAL_BYPASS"
		(at 220.98 172.72 180)
		(effects
			(font
				(size 1.27 1.27)
			)
			(justify right bottom)
		)
	)
	(label "50MHZ_XTAL.+"
		(at 220.98 167.64 180)
		(effects
			(font
				(size 1.27 1.27)
			)
			(justify right bottom)
		)
	)
	(label "PHY_TDO"
		(at 220.98 241.3 180)
		(effects
			(font
				(size 1.27 1.27)
			)
			(justify right bottom)
		)
	)
	(label "NCSI.TX_EN"
		(at 134.62 68.58 0)
		(effects
			(font
				(size 1.27 1.27)
			)
			(justify left bottom)
		)
	)
	(label "NCSI.TXD_0"
		(at 134.62 71.12 0)
		(effects
			(font
				(size 1.27 1.27)
			)
			(justify left bottom)
		)
	)
	(label "AUX_PWR"
		(at 226.06 124.46 180)
		(effects
			(font
				(size 1.27 1.27)
			)
			(justify right bottom)
		)
	)
	(label "RSVD_J11_VSS"
		(at 220.98 218.44 180)
		(effects
			(font
				(size 1.27 1.27)
			)
			(justify right bottom)
		)
	)
	(label "NCSI.TXD_1"
		(at 134.62 76.2 0)
		(effects
			(font
				(size 1.27 1.27)
			)
			(justify left bottom)
		)
	)
	(label "~{PHY_TRST}"
		(at 220.98 231.14 180)
		(effects
			(font
				(size 1.27 1.27)
			)
			(justify right bottom)
		)
	)
	(label "GPIO5_POR_BYPASS"
		(at 113.03 127 0)
		(effects
			(font
				(size 1.27 1.27)
			)
			(justify left bottom)
		)
	)
	(label "PHY_TMS"
		(at 220.98 236.22 180)
		(effects
			(font
				(size 1.27 1.27)
			)
			(justify right bottom)
		)
	)
	(label "NCSI.RXD_1"
		(at 134.62 78.74 0)
		(effects
			(font
				(size 1.27 1.27)
			)
			(justify left bottom)
		)
	)
	(label "MDIO_I2C.MDIO"
		(at 86.36 198.12 0)
		(effects
			(font
				(size 1.27 1.27)
			)
			(justify left bottom)
		)
	)
	(label "NCSI.CRS_DV"
		(at 134.62 66.04 0)
		(effects
			(font
				(size 1.27 1.27)
			)
			(justify left bottom)
		)
	)
	(label "REFCLK_SEL"
		(at 220.98 175.26 180)
		(effects
			(font
				(size 1.27 1.27)
			)
			(justify right bottom)
		)
	)
	(label "PHY_TDI"
		(at 220.98 238.76 180)
		(effects
			(font
				(size 1.27 1.27)
			)
			(justify right bottom)
		)
	)
	(label "FLSH_SCK"
		(at 276.86 124.46 0)
		(effects
			(font
				(size 1.27 1.27)
			)
			(justify left bottom)
		)
	)
	(label "MDIO_I2C.MDC"
		(at 86.36 195.58 0)
		(effects
			(font
				(size 1.27 1.27)
			)
			(justify left bottom)
		)
	)
	(label "50MHZ_XTAL_R.+"
		(at 186.69 167.64 180)
		(effects
			(font
				(size 1.27 1.27)
			)
			(justify right bottom)
		)
	)
	(label "~{PCI_DIS}"
		(at 226.06 116.84 180)
		(effects
			(font
				(size 1.27 1.27)
			)
			(justify right bottom)
		)
	)
	(label "MAIN_PWR_OK"
		(at 226.06 121.92 180)
		(effects
			(font
				(size 1.27 1.27)
			)
			(justify right bottom)
		)
	)
	(label "FLASH.MISO"
		(at 331.47 129.54 0)
		(effects
			(font
				(size 1.27 1.27)
			)
			(justify left bottom)
		)
	)
	(label "RSVDK40_1P88V"
		(at 285.75 215.9 0)
		(effects
			(font
				(size 1.27 1.27)
			)
			(justify left bottom)
		)
	)
	(label "POR_BYPASS"
		(at 226.06 127 180)
		(effects
			(font
				(size 1.27 1.27)
			)
			(justify right bottom)
		)
	)
	(label "MDIO.MDC"
		(at 142.24 195.58 0)
		(effects
			(font
				(size 1.27 1.27)
			)
			(justify left bottom)
		)
	)
	(label "FLASH.~{CE}"
		(at 331.47 121.92 0)
		(effects
			(font
				(size 1.27 1.27)
			)
			(justify left bottom)
		)
	)
	(label "RSVDL33"
		(at 223.52 200.66 180)
		(effects
			(font
				(size 1.27 1.27)
			)
			(justify right bottom)
		)
	)
	(label "MDIO.MDIO"
		(at 142.24 198.12 0)
		(effects
			(font
				(size 1.27 1.27)
			)
			(justify left bottom)
		)
	)
	(label "PHY_TCK"
		(at 220.98 233.68 180)
		(effects
			(font
				(size 1.27 1.27)
			)
			(justify right bottom)
		)
	)
	(label "NCSI.RXD_0"
		(at 134.62 73.66 0)
		(effects
			(font
				(size 1.27 1.27)
			)
			(justify left bottom)
		)
	)
	(label "LAN_PWR_GOOD"
		(at 226.06 129.54 180)
		(effects
			(font
				(size 1.27 1.27)
			)
			(justify right bottom)
		)
	)
	(label "~{SMBALRT}"
		(at 276.86 106.68 0)
		(effects
			(font
				(size 1.27 1.27)
			)
			(justify left bottom)
		)
	)
	(label "NCSI.REF_CLK"
		(at 134.62 63.5 0)
		(effects
			(font
				(size 1.27 1.27)
			)
			(justify left bottom)
		)
	)
	(label "50MHZ_XTAL.-"
		(at 220.98 170.18 180)
		(effects
			(font
				(size 1.27 1.27)
			)
			(justify right bottom)
		)
	)
	(label "FLASH.MOSI"
		(at 331.47 127 0)
		(effects
			(font
				(size 1.27 1.27)
			)
			(justify left bottom)
		)
	)
	(label "NCSI.ARB_OUT"
		(at 134.62 60.96 0)
		(effects
			(font
				(size 1.27 1.27)
			)
			(justify left bottom)
		)
	)
	(label "FLASH.CLK"
		(at 331.47 124.46 0)
		(effects
			(font
				(size 1.27 1.27)
			)
			(justify left bottom)
		)
	)
	(label "GPIO5_POR_BYPASS"
		(at 303.53 93.98 180)
		(effects
			(font
				(size 1.27 1.27)
			)
			(justify right bottom)
		)
	)
	(label "~{DEV_DIS}"
		(at 226.06 114.3 180)
		(effects
			(font
				(size 1.27 1.27)
			)
			(justify right bottom)
		)
	)
	(label "50MHZ_XTAL_R.-"
		(at 186.69 170.18 180)
		(effects
			(font
				(size 1.27 1.27)
			)
			(justify right bottom)
		)
	)
	(label "NCSI.ARB_IN"
		(at 134.62 58.42 0)
		(effects
			(font
				(size 1.27 1.27)
			)
			(justify left bottom)
		)
	)
	(label "~{PHY_RESET}"
		(at 220.98 223.52 180)
		(effects
			(font
				(size 1.27 1.27)
			)
			(justify right bottom)
		)
	)
	(hierarchical_label "FLASH{SPI}"
		(shape bidirectional)
		(at 350.52 137.16 0)
		(effects
			(font
				(size 1.27 1.27)
			)
			(justify left)
		)
	)
	(hierarchical_label "P1_INT_MLC"
		(shape output)
		(at 288.29 170.18 0)
		(effects
			(font
				(size 1.27 1.27)
			)
			(justify left)
		)
	)
	(hierarchical_label "~{PE_RST}"
		(shape input)
		(at 66.04 129.54 180)
		(effects
			(font
				(size 1.27 1.27)
			)
			(justify right)
		)
	)
	(hierarchical_label "~{P1_LINK_LESS_THAN_10G}"
		(shape output)
		(at 278.13 86.36 0)
		(effects
			(font
				(size 1.27 1.27)
			)
			(justify left)
		)
	)
	(hierarchical_label "~{PHY_RESET_3V3}"
		(shape input)
		(at 91.44 237.49 180)
		(effects
			(font
				(size 1.27 1.27)
			)
			(justify right)
		)
	)
	(hierarchical_label "~{P0_LINK_LESS_THAN_10G}"
		(shape output)
		(at 278.13 81.28 0)
		(effects
			(font
				(size 1.27 1.27)
			)
			(justify left)
		)
	)
	(hierarchical_label "MDIO_I2C{MDIO}"
		(shape bidirectional)
		(at 77.47 205.74 180)
		(effects
			(font
				(size 1.27 1.27)
			)
			(justify right)
		)
	)
	(hierarchical_label "P0_INT_MLC"
		(shape output)
		(at 288.29 167.64 0)
		(effects
			(font
				(size 1.27 1.27)
			)
			(justify left)
		)
	)
	(symbol
		(lib_id "antmicroResistors0402:R_100k_0402")
		(at 168.91 55.88 90)
		(unit 1)
		(exclude_from_sim no)
		(in_bom yes)
		(on_board yes)
		(dnp no)
		(property "Reference" "R151"
			(at 170.434 52.07 90)
			(effects
				(font
					(size 1.27 1.27)
					(thickness 0.15)
				)
				(justify right)
			)
		)
		(property "Value" "R_100k_0402"
			(at 181.61 35.56 0)
			(effects
				(font
					(size 1.27 1.27)
					(thickness 0.15)
				)
				(justify left bottom)
				(hide yes)
			)
		)
		(property "Footprint" "antmicro-footprints:R_0402_1005Metric"
			(at 184.15 35.56 0)
			(effects
				(font
					(size 1.27 1.27)
					(thickness 0.15)
				)
				(justify left bottom)
				(hide yes)
			)
		)
		(property "Datasheet" "https://www.bourns.com/docs/product-datasheets/cr.pdf"
			(at 186.69 35.56 0)
			(effects
				(font
					(size 1.27 1.27)
					(thickness 0.15)
				)
				(justify left bottom)
				(hide yes)
			)
		)
		(property "Description" "SMD Chip Resistor, 100 kohm, ± 1%, 62.5 mW, 0402 [1005 Metric], Thick Film, General Purpose"
			(at 168.91 55.88 0)
			(effects
				(font
					(size 1.27 1.27)
				)
				(hide yes)
			)
		)
		(property "MPN" "CR0402-FX-1003GLF"
			(at 189.23 35.56 0)
			(effects
				(font
					(size 1.27 1.27)
					(thickness 0.15)
				)
				(justify left bottom)
				(hide yes)
			)
		)
		(property "Manufacturer" "Bourns"
			(at 191.77 35.56 0)
			(effects
				(font
					(size 1.27 1.27)
					(thickness 0.15)
				)
				(justify left bottom)
				(hide yes)
			)
		)
		(property "License" "Apache-2.0"
			(at 194.31 35.56 0)
			(effects
				(font
					(size 1.27 1.27)
					(thickness 0.15)
				)
				(justify left bottom)
				(hide yes)
			)
		)
		(property "Author" "Antmicro"
			(at 196.85 35.56 0)
			(effects
				(font
					(size 1.27 1.27)
					(thickness 0.15)
				)
				(justify left bottom)
				(hide yes)
			)
		)
		(property "Val" "100k"
			(at 170.434 54.61 90)
			(effects
				(font
					(size 1.27 1.27)
					(thickness 0.15)
				)
				(justify right)
			)
		)
		(property "Tolerance" "1%"
			(at 179.07 35.56 0)
			(effects
				(font
					(size 1.27 1.27)
				)
				(justify left bottom)
				(hide yes)
			)
		)
		(pin "2"
		)
		(pin "1"
		)
		(instances
			(project "OCuLink to 10GbE adapter"
				(path ""
					(reference "R80")
					(unit 1)
				)
			)
			(project "thunderbolt-to-10gbe-adapter"
				(path ""
					(reference "R151")
					(unit 1)
				)
			)
		)
	)
	(symbol
		(lib_id "antmicroCapacitors0402:C_100n_0402")
		(at 73.66 119.38 90)
		(unit 1)
		(exclude_from_sim no)
		(in_bom yes)
		(on_board yes)
		(dnp no)
		(fields_autoplaced yes)
		(property "Reference" "C274"
			(at 76.2 115.5636 90)
			(effects
				(font
					(size 1.27 1.27)
					(thickness 0.15)
				)
				(justify right)
			)
		)
		(property "Value" "C_100n_0402"
			(at 96.52 104.14 0)
			(effects
				(font
					(size 1.27 1.27)
					(thickness 0.15)
				)
				(justify left bottom)
				(hide yes)
			)
		)
		(property "Footprint" "antmicro-footprints:C_0402_1005Metric"
			(at 99.06 104.14 0)
			(effects
				(font
					(size 1.27 1.27)
					(thickness 0.15)
				)
				(justify left bottom)
				(hide yes)
			)
		)
		(property "Datasheet" "https://www.murata.com/products/productdetail?partno=GRM155R61H104KE14%23"
			(at 101.6 104.14 0)
			(effects
				(font
					(size 1.27 1.27)
					(thickness 0.15)
				)
				(justify left bottom)
				(hide yes)
			)
		)
		(property "Description" "SMD Multilayer Ceramic Capacitor, 0.1 µF, 50 V, 0402 [1005 Metric], ± 10%, X5R, GRM Series"
			(at 73.66 119.38 0)
			(effects
				(font
					(size 1.27 1.27)
				)
				(hide yes)
			)
		)
		(property "MPN" "GRM155R61H104KE14D"
			(at 104.14 104.14 0)
			(effects
				(font
					(size 1.27 1.27)
					(thickness 0.15)
				)
				(justify left bottom)
				(hide yes)
			)
		)
		(property "Val" "100n"
			(at 76.2 118.1036 90)
			(effects
				(font
					(size 1.27 1.27)
					(thickness 0.15)
				)
				(justify right)
			)
		)
		(property "Voltage" "50V"
			(at 83.82 104.14 0)
			(effects
				(font
					(size 1.27 1.27)
					(thickness 0.15)
				)
				(justify left bottom)
				(hide yes)
			)
		)
		(property "Dielectric" "X5R"
			(at 86.36 104.14 0)
			(effects
				(font
					(size 1.27 1.27)
					(thickness 0.15)
				)
				(justify left bottom)
				(hide yes)
			)
		)
		(property "Manufacturer" "Murata"
			(at 88.9 104.14 0)
			(effects
				(font
					(size 1.27 1.27)
					(thickness 0.15)
				)
				(justify left bottom)
				(hide yes)
			)
		)
		(property "License" "Apache-2.0"
			(at 91.44 104.14 0)
			(effects
				(font
					(size 1.27 1.27)
					(thickness 0.15)
				)
				(justify left bottom)
				(hide yes)
			)
		)
		(property "Author" "Antmicro"
			(at 93.98 104.14 0)
			(effects
				(font
					(size 1.27 1.27)
					(thickness 0.15)
				)
				(justify left bottom)
				(hide yes)
			)
		)
		(pin "2"
		)
		(pin "1"
		)
		(instances
			(project ""
				(path ""
					(reference "C198")
					(unit 1)
				)
			)
			(project "thunderbolt-to-10gbe-adapter"
				(path ""
					(reference "C274")
					(unit 1)
				)
			)
		)
	)
	(symbol
		(lib_id "antmicropower:+3V3")
		(at 285.75 154.94 0)
		(unit 1)
		(exclude_from_sim no)
		(in_bom yes)
		(on_board yes)
		(dnp no)
		(property "Reference" "#PWR0409"
			(at 300.99 154.94 0)
			(effects
				(font
					(size 1.27 1.27)
					(thickness 0.15)
				)
				(justify left bottom)
				(hide yes)
			)
		)
		(property "Value" "+3V3"
			(at 285.75 151.13 0)
			(effects
				(font
					(size 1.27 1.27)
					(thickness 0.15)
				)
			)
		)
		(property "Footprint" ""
			(at 300.99 162.56 0)
			(effects
				(font
					(size 1.27 1.27)
					(thickness 0.15)
				)
				(justify left bottom)
				(hide yes)
			)
		)
		(property "Datasheet" ""
			(at 300.99 165.1 0)
			(effects
				(font
					(size 1.27 1.27)
					(thickness 0.15)
				)
				(justify left bottom)
				(hide yes)
			)
		)
		(property "Description" ""
			(at 285.75 154.94 0)
			(effects
				(font
					(size 1.27 1.27)
				)
				(hide yes)
			)
		)
		(property "Author" "Antmicro"
			(at 300.99 157.48 0)
			(effects
				(font
					(size 1.27 1.27)
					(thickness 0.15)
				)
				(justify left bottom)
				(hide yes)
			)
		)
		(property "License" "Apache-2.0"
			(at 300.99 160.02 0)
			(effects
				(font
					(size 1.27 1.27)
					(thickness 0.15)
				)
				(justify left bottom)
				(hide yes)
			)
		)
		(pin "1"
		)
		(instances
			(project "OCuLink to 10GbE adapter"
				(path ""
					(reference "#PWR0275")
					(unit 1)
				)
			)
			(project "thunderbolt-to-10gbe-adapter"
				(path ""
					(reference "#PWR0409")
					(unit 1)
				)
			)
		)
	)
	(symbol
		(lib_id "antmicroResistors0402:R_10R_0402")
		(at 191.77 170.18 0)
		(unit 1)
		(exclude_from_sim no)
		(in_bom yes)
		(on_board yes)
		(dnp no)
		(property "Reference" "R165"
			(at 191.77 168.91 0)
			(effects
				(font
					(size 1.27 1.27)
					(thickness 0.15)
				)
				(justify right)
			)
		)
		(property "Value" "R_10R_0402"
			(at 212.09 182.88 0)
			(effects
				(font
					(size 1.27 1.27)
					(thickness 0.15)
				)
				(justify left bottom)
				(hide yes)
			)
		)
		(property "Footprint" "antmicro-footprints:R_0402_1005Metric"
			(at 212.09 185.42 0)
			(effects
				(font
					(size 1.27 1.27)
					(thickness 0.15)
				)
				(justify left bottom)
				(hide yes)
			)
		)
		(property "Datasheet" "https://www.bourns.com/docs/product-datasheets/cr.pdf"
			(at 212.09 187.96 0)
			(effects
				(font
					(size 1.27 1.27)
					(thickness 0.15)
				)
				(justify left bottom)
				(hide yes)
			)
		)
		(property "Description" "SMD Chip Resistor, 10 ohm, ± 1%, 62.5 mW, 0402 [1005 Metric], Thick Film, General Purpose"
			(at 191.77 170.18 0)
			(effects
				(font
					(size 1.27 1.27)
				)
				(hide yes)
			)
		)
		(property "MPN" "CR0402-FX-10R0GLF"
			(at 212.09 190.5 0)
			(effects
				(font
					(size 1.27 1.27)
					(thickness 0.15)
				)
				(justify left bottom)
				(hide yes)
			)
		)
		(property "Manufacturer" "Bourns"
			(at 212.09 193.04 0)
			(effects
				(font
					(size 1.27 1.27)
					(thickness 0.15)
				)
				(justify left bottom)
				(hide yes)
			)
		)
		(property "License" "Apache-2.0"
			(at 212.09 195.58 0)
			(effects
				(font
					(size 1.27 1.27)
					(thickness 0.15)
				)
				(justify left bottom)
				(hide yes)
			)
		)
		(property "Author" "Antmicro"
			(at 212.09 198.12 0)
			(effects
				(font
					(size 1.27 1.27)
					(thickness 0.15)
				)
				(justify left bottom)
				(hide yes)
			)
		)
		(property "Val" "10R"
			(at 196.85 168.91 0)
			(effects
				(font
					(size 1.27 1.27)
					(thickness 0.15)
				)
				(justify left)
			)
		)
		(property "Tolerance" "1%"
			(at 212.09 180.34 0)
			(effects
				(font
					(size 1.27 1.27)
				)
				(justify left bottom)
				(hide yes)
			)
		)
		(pin "1"
		)
		(pin "2"
		)
		(instances
			(project "OCuLink to 10GbE adapter"
				(path ""
					(reference "R48")
					(unit 1)
				)
			)
			(project "thunderbolt-to-10gbe-adapter"
				(path ""
					(reference "R165")
					(unit 1)
				)
			)
		)
	)
	(symbol
		(lib_id "antmicroResistors0402:R_1k_0402")
		(at 189.23 180.34 90)
		(unit 1)
		(exclude_from_sim no)
		(in_bom yes)
		(on_board yes)
		(dnp no)
		(property "Reference" "R162"
			(at 190.754 176.53 90)
			(effects
				(font
					(size 1.27 1.27)
					(thickness 0.15)
				)
				(justify right)
			)
		)
		(property "Value" "R_1k_0402"
			(at 201.93 160.02 0)
			(effects
				(font
					(size 1.27 1.27)
					(thickness 0.15)
				)
				(justify left bottom)
				(hide yes)
			)
		)
		(property "Footprint" "antmicro-footprints:R_0402_1005Metric"
			(at 204.47 160.02 0)
			(effects
				(font
					(size 1.27 1.27)
					(thickness 0.15)
				)
				(justify left bottom)
				(hide yes)
			)
		)
		(property "Datasheet" "https://www.bourns.com/docs/product-datasheets/cr.pdf"
			(at 207.01 160.02 0)
			(effects
				(font
					(size 1.27 1.27)
					(thickness 0.15)
				)
				(justify left bottom)
				(hide yes)
			)
		)
		(property "Description" "SMD Chip Resistor, 1 kohm, ± 1%, 63 mW, 0402 [1005 Metric], Thick Film, General Purpose"
			(at 189.23 180.34 0)
			(effects
				(font
					(size 1.27 1.27)
				)
				(hide yes)
			)
		)
		(property "MPN" "CR0402-FX-1001GLF"
			(at 209.55 160.02 0)
			(effects
				(font
					(size 1.27 1.27)
					(thickness 0.15)
				)
				(justify left bottom)
				(hide yes)
			)
		)
		(property "Manufacturer" "Bourns"
			(at 212.09 160.02 0)
			(effects
				(font
					(size 1.27 1.27)
					(thickness 0.15)
				)
				(justify left bottom)
				(hide yes)
			)
		)
		(property "License" "Apache-2.0"
			(at 214.63 160.02 0)
			(effects
				(font
					(size 1.27 1.27)
					(thickness 0.15)
				)
				(justify left bottom)
				(hide yes)
			)
		)
		(property "Author" "Antmicro"
			(at 217.17 160.02 0)
			(effects
				(font
					(size 1.27 1.27)
					(thickness 0.15)
				)
				(justify left bottom)
				(hide yes)
			)
		)
		(property "Val" "1k"
			(at 190.754 179.07 90)
			(effects
				(font
					(size 1.27 1.27)
					(thickness 0.15)
				)
				(justify right)
			)
		)
		(property "Tolerance" "1%"
			(at 199.39 160.02 0)
			(effects
				(font
					(size 1.27 1.27)
				)
				(justify left bottom)
				(hide yes)
			)
		)
		(pin "1"
		)
		(pin "2"
		)
		(instances
			(project "OCuLink to 10GbE adapter"
				(path ""
					(reference "R113")
					(unit 1)
				)
			)
			(project "thunderbolt-to-10gbe-adapter"
				(path ""
					(reference "R162")
					(unit 1)
				)
			)
		)
	)
	(symbol
		(lib_id "antmicropower:GND")
		(at 171.45 88.9 0)
		(unit 1)
		(exclude_from_sim no)
		(in_bom yes)
		(on_board yes)
		(dnp no)
		(property "Reference" "#PWR0395"
			(at 180.34 91.44 0)
			(effects
				(font
					(size 1.27 1.27)
					(thickness 0.15)
				)
				(justify left bottom)
				(hide yes)
			)
		)
		(property "Value" "GND"
			(at 171.45 92.71 0)
			(effects
				(font
					(size 1.27 1.27)
					(thickness 0.15)
				)
			)
		)
		(property "Footprint" ""
			(at 180.34 96.52 0)
			(effects
				(font
					(size 1.27 1.27)
					(thickness 0.15)
				)
				(justify left bottom)
				(hide yes)
			)
		)
		(property "Datasheet" ""
			(at 180.34 101.6 0)
			(effects
				(font
					(size 1.27 1.27)
					(thickness 0.15)
				)
				(justify left bottom)
				(hide yes)
			)
		)
		(property "Description" ""
			(at 171.45 88.9 0)
			(effects
				(font
					(size 1.27 1.27)
				)
				(hide yes)
			)
		)
		(property "Author" "Antmicro"
			(at 180.34 96.52 0)
			(effects
				(font
					(size 1.27 1.27)
					(thickness 0.15)
				)
				(justify left bottom)
				(hide yes)
			)
		)
		(property "License" "Apache-2.0"
			(at 180.34 99.06 0)
			(effects
				(font
					(size 1.27 1.27)
					(thickness 0.15)
				)
				(justify left bottom)
				(hide yes)
			)
		)
		(pin "1"
		)
		(instances
			(project "OCuLink to 10GbE adapter"
				(path ""
					(reference "#PWR0260")
					(unit 1)
				)
			)
			(project "thunderbolt-to-10gbe-adapter"
				(path ""
					(reference "#PWR0395")
					(unit 1)
				)
			)
		)
	)
	(symbol
		(lib_id "antmicroResistors0402:R_10k_0402")
		(at 306.07 104.14 90)
		(unit 1)
		(exclude_from_sim no)
		(in_bom yes)
		(on_board yes)
		(dnp no)
		(property "Reference" "R180"
			(at 307.594 100.33 90)
			(effects
				(font
					(size 1.27 1.27)
					(thickness 0.15)
				)
				(justify right)
			)
		)
		(property "Value" "R_10k_0402"
			(at 318.77 83.82 0)
			(effects
				(font
					(size 1.27 1.27)
					(thickness 0.15)
				)
				(justify left bottom)
				(hide yes)
			)
		)
		(property "Footprint" "antmicro-footprints:R_0402_1005Metric"
			(at 321.31 83.82 0)
			(effects
				(font
					(size 1.27 1.27)
					(thickness 0.15)
				)
				(justify left bottom)
				(hide yes)
			)
		)
		(property "Datasheet" "https://www.bourns.com/docs/product-datasheets/cr.pdf"
			(at 323.85 83.82 0)
			(effects
				(font
					(size 1.27 1.27)
					(thickness 0.15)
				)
				(justify left bottom)
				(hide yes)
			)
		)
		(property "Description" "SMD Chip Resistor, 10 kohm, ± 1%, 62.5 mW, 0402 [1005 Metric], Thick Film, General Purpose"
			(at 306.07 104.14 0)
			(effects
				(font
					(size 1.27 1.27)
				)
				(hide yes)
			)
		)
		(property "MPN" "CR0402-FX-1002GLF"
			(at 326.39 83.82 0)
			(effects
				(font
					(size 1.27 1.27)
					(thickness 0.15)
				)
				(justify left bottom)
				(hide yes)
			)
		)
		(property "Manufacturer" "Bourns"
			(at 328.93 83.82 0)
			(effects
				(font
					(size 1.27 1.27)
					(thickness 0.15)
				)
				(justify left bottom)
				(hide yes)
			)
		)
		(property "License" "Apache-2.0"
			(at 331.47 83.82 0)
			(effects
				(font
					(size 1.27 1.27)
					(thickness 0.15)
				)
				(justify left bottom)
				(hide yes)
			)
		)
		(property "Author" "Antmicro"
			(at 334.01 83.82 0)
			(effects
				(font
					(size 1.27 1.27)
					(thickness 0.15)
				)
				(justify left bottom)
				(hide yes)
			)
		)
		(property "Val" "10k"
			(at 307.594 102.87 90)
			(effects
				(font
					(size 1.27 1.27)
					(thickness 0.15)
				)
				(justify right)
			)
		)
		(property "Tolerance" "1%"
			(at 316.23 83.82 0)
			(effects
				(font
					(size 1.27 1.27)
				)
				(justify left bottom)
				(hide yes)
			)
		)
		(pin "2"
		)
		(pin "1"
		)
		(instances
			(project ""
				(path ""
					(reference "R93")
					(unit 1)
				)
			)
			(project "thunderbolt-to-10gbe-adapter"
				(path ""
					(reference "R180")
					(unit 1)
				)
			)
		)
	)
	(symbol
		(lib_id "antmicroResistors0402:R_2k_0402")
		(at 93.98 228.6 270)
		(mirror x)
		(unit 1)
		(exclude_from_sim no)
		(in_bom yes)
		(on_board yes)
		(dnp no)
		(property "Reference" "R139"
			(at 92.71 224.79 90)
			(effects
				(font
					(size 1.27 1.27)
					(thickness 0.15)
				)
				(justify right)
			)
		)
		(property "Value" "R_2k_0402"
			(at 81.28 208.28 0)
			(effects
				(font
					(size 1.27 1.27)
					(thickness 0.15)
				)
				(justify left bottom)
				(hide yes)
			)
		)
		(property "Footprint" "antmicro-footprints:R_0402_1005Metric"
			(at 78.74 208.28 0)
			(effects
				(font
					(size 1.27 1.27)
					(thickness 0.15)
				)
				(justify left bottom)
				(hide yes)
			)
		)
		(property "Datasheet" "https://www.bourns.com/docs/product-datasheets/cr.pdf"
			(at 76.2 208.28 0)
			(effects
				(font
					(size 1.27 1.27)
					(thickness 0.15)
				)
				(justify left bottom)
				(hide yes)
			)
		)
		(property "Description" "SMD Chip Resistor, 2 kohm, ± 1%, 62.5 mW, 0402 [1005 Metric], Thick Film, General Purpose"
			(at 63.5 208.28 0)
			(effects
				(font
					(size 1.27 1.27)
				)
				(justify left bottom)
				(hide yes)
			)
		)
		(property "MPN" "CR0402-FX-2001GLF"
			(at 73.66 208.28 0)
			(effects
				(font
					(size 1.27 1.27)
					(thickness 0.15)
				)
				(justify left bottom)
				(hide yes)
			)
		)
		(property "Manufacturer" "Bourns"
			(at 71.12 208.28 0)
			(effects
				(font
					(size 1.27 1.27)
					(thickness 0.15)
				)
				(justify left bottom)
				(hide yes)
			)
		)
		(property "License" "Apache-2.0"
			(at 68.58 208.28 0)
			(effects
				(font
					(size 1.27 1.27)
					(thickness 0.15)
				)
				(justify left bottom)
				(hide yes)
			)
		)
		(property "Author" "Antmicro"
			(at 66.04 208.28 0)
			(effects
				(font
					(size 1.27 1.27)
					(thickness 0.15)
				)
				(justify left bottom)
				(hide yes)
			)
		)
		(property "Val" "2k"
			(at 92.71 227.33 90)
			(effects
				(font
					(size 1.27 1.27)
					(thickness 0.15)
				)
				(justify right)
			)
		)
		(property "Tolerance" "1%"
			(at 83.82 208.28 0)
			(effects
				(font
					(size 1.27 1.27)
				)
				(justify left bottom)
				(hide yes)
			)
		)
		(pin "2"
		)
		(pin "1"
		)
		(instances
			(project "OCuLink to 10GbE adapter"
				(path ""
					(reference "R171")
					(unit 1)
				)
			)
			(project "thunderbolt-to-10gbe-adapter"
				(path ""
					(reference "R139")
					(unit 1)
				)
			)
		)
	)
	(symbol
		(lib_id "antmicropower:GND")
		(at 283.21 254 0)
		(unit 1)
		(exclude_from_sim no)
		(in_bom yes)
		(on_board yes)
		(dnp no)
		(property "Reference" "#PWR0408"
			(at 292.1 256.54 0)
			(effects
				(font
					(size 1.27 1.27)
					(thickness 0.15)
				)
				(justify left bottom)
				(hide yes)
			)
		)
		(property "Value" "GND"
			(at 283.21 257.81 0)
			(effects
				(font
					(size 1.27 1.27)
					(thickness 0.15)
				)
			)
		)
		(property "Footprint" ""
			(at 292.1 261.62 0)
			(effects
				(font
					(size 1.27 1.27)
					(thickness 0.15)
				)
				(justify left bottom)
				(hide yes)
			)
		)
		(property "Datasheet" ""
			(at 292.1 266.7 0)
			(effects
				(font
					(size 1.27 1.27)
					(thickness 0.15)
				)
				(justify left bottom)
				(hide yes)
			)
		)
		(property "Description" ""
			(at 283.21 254 0)
			(effects
				(font
					(size 1.27 1.27)
				)
				(hide yes)
			)
		)
		(property "Author" "Antmicro"
			(at 292.1 261.62 0)
			(effects
				(font
					(size 1.27 1.27)
					(thickness 0.15)
				)
				(justify left bottom)
				(hide yes)
			)
		)
		(property "License" "Apache-2.0"
			(at 292.1 264.16 0)
			(effects
				(font
					(size 1.27 1.27)
					(thickness 0.15)
				)
				(justify left bottom)
				(hide yes)
			)
		)
		(pin "1"
		)
		(instances
			(project "OCuLink to 10GbE adapter"
				(path ""
					(reference "#PWR0284")
					(unit 1)
				)
			)
			(project "thunderbolt-to-10gbe-adapter"
				(path ""
					(reference "#PWR0408")
					(unit 1)
				)
			)
		)
	)
	(symbol
		(lib_id "antmicropower:GND")
		(at 102.87 189.23 0)
		(mirror y)
		(unit 1)
		(exclude_from_sim no)
		(in_bom yes)
		(on_board yes)
		(dnp no)
		(property "Reference" "#PWR0375"
			(at 93.98 191.77 0)
			(effects
				(font
					(size 1.27 1.27)
					(thickness 0.15)
				)
				(justify left bottom)
				(hide yes)
			)
		)
		(property "Value" "GND"
			(at 102.87 193.04 0)
			(effects
				(font
					(size 1.27 1.27)
					(thickness 0.15)
				)
			)
		)
		(property "Footprint" ""
			(at 93.98 196.85 0)
			(effects
				(font
					(size 1.27 1.27)
					(thickness 0.15)
				)
				(justify left bottom)
				(hide yes)
			)
		)
		(property "Datasheet" ""
			(at 93.98 201.93 0)
			(effects
				(font
					(size 1.27 1.27)
					(thickness 0.15)
				)
				(justify left bottom)
				(hide yes)
			)
		)
		(property "Description" ""
			(at 102.87 189.23 0)
			(effects
				(font
					(size 1.27 1.27)
				)
				(hide yes)
			)
		)
		(property "Author" "Antmicro"
			(at 93.98 196.85 0)
			(effects
				(font
					(size 1.27 1.27)
					(thickness 0.15)
				)
				(justify left bottom)
				(hide yes)
			)
		)
		(property "License" "Apache-2.0"
			(at 93.98 199.39 0)
			(effects
				(font
					(size 1.27 1.27)
					(thickness 0.15)
				)
				(justify left bottom)
				(hide yes)
			)
		)
		(pin "1"
		)
		(instances
			(project "OCuLink to 10GbE adapter"
				(path ""
					(reference "#PWR0110")
					(unit 1)
				)
			)
			(project "thunderbolt-to-10gbe-adapter"
				(path ""
					(reference "#PWR0375")
					(unit 1)
				)
			)
		)
	)
	(symbol
		(lib_id "antmicroTestPoints:TP_0.75mm_SMD")
		(at 322.58 111.76 0)
		(unit 1)
		(exclude_from_sim no)
		(in_bom no)
		(on_board yes)
		(dnp no)
		(fields_autoplaced yes)
		(property "Reference" "TP36"
			(at 327.66 111.76 0)
			(effects
				(font
					(size 1.27 1.27)
					(thickness 0.15)
				)
				(justify left)
			)
		)
		(property "Value" "TP_0.75mm_SMD"
			(at 332.74 115.57 0)
			(effects
				(font
					(size 1.27 1.27)
					(thickness 0.15)
				)
				(justify left bottom)
				(hide yes)
			)
		)
		(property "Footprint" "antmicro-footprints:TP_SMD_0.75mm"
			(at 332.74 118.11 0)
			(effects
				(font
					(size 1.27 1.27)
					(thickness 0.15)
				)
				(justify left bottom)
				(hide yes)
			)
		)
		(property "Datasheet" ""
			(at 340.36 124.46 0)
			(effects
				(font
					(size 1.27 1.27)
					(thickness 0.15)
				)
				(justify left bottom)
				(hide yes)
			)
		)
		(property "Description" "SMT test point"
			(at 333.375 125.73 0)
			(effects
				(font
					(size 1.27 1.27)
				)
				(justify left bottom)
				(hide yes)
			)
		)
		(property "MPN" ""
			(at 333.375 123.19 0)
			(effects
				(font
					(size 1.27 1.27)
					(thickness 0.15)
				)
				(justify left bottom)
				(hide yes)
			)
		)
		(property "Manufacturer" ""
			(at 333.375 118.11 0)
			(effects
				(font
					(size 1.27 1.27)
					(thickness 0.15)
				)
				(justify left bottom)
				(hide yes)
			)
		)
		(property "Author" "Antmicro"
			(at 332.74 120.65 0)
			(effects
				(font
					(size 1.27 1.27)
					(thickness 0.15)
				)
				(justify left bottom)
				(hide yes)
			)
		)
		(property "License" "Apache-2.0"
			(at 332.74 123.19 0)
			(effects
				(font
					(size 1.27 1.27)
					(thickness 0.15)
				)
				(justify left bottom)
				(hide yes)
			)
		)
		(pin "1"
		)
		(instances
			(project "thunderbolt-to-10gbe-adapter"
				(path ""
					(reference "TP36")
					(unit 1)
				)
			)
		)
	)
	(symbol
		(lib_id "antmicropower:GND")
		(at 186.69 139.7 0)
		(unit 1)
		(exclude_from_sim no)
		(in_bom yes)
		(on_board yes)
		(dnp no)
		(property "Reference" "#PWR0401"
			(at 195.58 142.24 0)
			(effects
				(font
					(size 1.27 1.27)
					(thickness 0.15)
				)
				(justify left bottom)
				(hide yes)
			)
		)
		(property "Value" "GND"
			(at 186.69 143.51 0)
			(effects
				(font
					(size 1.27 1.27)
					(thickness 0.15)
				)
			)
		)
		(property "Footprint" ""
			(at 195.58 147.32 0)
			(effects
				(font
					(size 1.27 1.27)
					(thickness 0.15)
				)
				(justify left bottom)
				(hide yes)
			)
		)
		(property "Datasheet" ""
			(at 195.58 152.4 0)
			(effects
				(font
					(size 1.27 1.27)
					(thickness 0.15)
				)
				(justify left bottom)
				(hide yes)
			)
		)
		(property "Description" ""
			(at 186.69 139.7 0)
			(effects
				(font
					(size 1.27 1.27)
				)
				(hide yes)
			)
		)
		(property "Author" "Antmicro"
			(at 195.58 147.32 0)
			(effects
				(font
					(size 1.27 1.27)
					(thickness 0.15)
				)
				(justify left bottom)
				(hide yes)
			)
		)
		(property "License" "Apache-2.0"
			(at 195.58 149.86 0)
			(effects
				(font
					(size 1.27 1.27)
					(thickness 0.15)
				)
				(justify left bottom)
				(hide yes)
			)
		)
		(pin "1"
		)
		(instances
			(project "OCuLink to 10GbE adapter"
				(path ""
					(reference "#PWR0272")
					(unit 1)
				)
			)
			(project "thunderbolt-to-10gbe-adapter"
				(path ""
					(reference "#PWR0401")
					(unit 1)
				)
			)
		)
	)
	(symbol
		(lib_id "antmicroResistors0402:R_100R_0402")
		(at 186.69 137.16 90)
		(unit 1)
		(exclude_from_sim no)
		(in_bom yes)
		(on_board yes)
		(dnp yes)
		(property "Reference" "R160"
			(at 188.214 133.35 90)
			(effects
				(font
					(size 1.27 1.27)
					(thickness 0.15)
				)
				(justify right)
			)
		)
		(property "Value" "R_100R_0402"
			(at 199.39 116.84 0)
			(effects
				(font
					(size 1.27 1.27)
					(thickness 0.15)
				)
				(justify left bottom)
				(hide yes)
			)
		)
		(property "Footprint" "antmicro-footprints:R_0402_1005Metric"
			(at 201.93 116.84 0)
			(effects
				(font
					(size 1.27 1.27)
					(thickness 0.15)
				)
				(justify left bottom)
				(hide yes)
			)
		)
		(property "Datasheet" "https://www.bourns.com/docs/product-datasheets/cr.pdf"
			(at 204.47 116.84 0)
			(effects
				(font
					(size 1.27 1.27)
					(thickness 0.15)
				)
				(justify left bottom)
				(hide yes)
			)
		)
		(property "Description" "SMD Chip Resistor, 100 ohm, ± 1%, 62.5 mW, 0402 [1005 Metric], Thick Film, General Purpose"
			(at 186.69 137.16 0)
			(effects
				(font
					(size 1.27 1.27)
				)
				(hide yes)
			)
		)
		(property "MPN" "CR0402-FX-1000GLF"
			(at 207.01 116.84 0)
			(effects
				(font
					(size 1.27 1.27)
					(thickness 0.15)
				)
				(justify left bottom)
				(hide yes)
			)
		)
		(property "Manufacturer" "Bourns"
			(at 209.55 116.84 0)
			(effects
				(font
					(size 1.27 1.27)
					(thickness 0.15)
				)
				(justify left bottom)
				(hide yes)
			)
		)
		(property "License" "Apache-2.0"
			(at 212.09 116.84 0)
			(effects
				(font
					(size 1.27 1.27)
					(thickness 0.15)
				)
				(justify left bottom)
				(hide yes)
			)
		)
		(property "Author" "Antmicro"
			(at 214.63 116.84 0)
			(effects
				(font
					(size 1.27 1.27)
					(thickness 0.15)
				)
				(justify left bottom)
				(hide yes)
			)
		)
		(property "Val" "100R"
			(at 188.214 135.89 90)
			(effects
				(font
					(size 1.27 1.27)
					(thickness 0.15)
				)
				(justify right)
			)
		)
		(property "Tolerance" "1%"
			(at 196.85 116.84 0)
			(effects
				(font
					(size 1.27 1.27)
				)
				(justify left bottom)
				(hide yes)
			)
		)
		(pin "2"
		)
		(pin "1"
		)
		(instances
			(project "OCuLink to 10GbE adapter"
				(path ""
					(reference "R108")
					(unit 1)
				)
			)
			(project "thunderbolt-to-10gbe-adapter"
				(path ""
					(reference "R160")
					(unit 1)
				)
			)
		)
	)
	(symbol
		(lib_id "antmicropower:GND")
		(at 168.91 182.88 0)
		(unit 1)
		(exclude_from_sim no)
		(in_bom yes)
		(on_board yes)
		(dnp no)
		(property "Reference" "#PWR0394"
			(at 177.8 185.42 0)
			(effects
				(font
					(size 1.27 1.27)
					(thickness 0.15)
				)
				(justify left bottom)
				(hide yes)
			)
		)
		(property "Value" "GND"
			(at 168.91 186.69 0)
			(effects
				(font
					(size 1.27 1.27)
					(thickness 0.15)
				)
			)
		)
		(property "Footprint" ""
			(at 177.8 190.5 0)
			(effects
				(font
					(size 1.27 1.27)
					(thickness 0.15)
				)
				(justify left bottom)
				(hide yes)
			)
		)
		(property "Datasheet" ""
			(at 177.8 195.58 0)
			(effects
				(font
					(size 1.27 1.27)
					(thickness 0.15)
				)
				(justify left bottom)
				(hide yes)
			)
		)
		(property "Description" ""
			(at 168.91 182.88 0)
			(effects
				(font
					(size 1.27 1.27)
				)
				(hide yes)
			)
		)
		(property "Author" "Antmicro"
			(at 177.8 190.5 0)
			(effects
				(font
					(size 1.27 1.27)
					(thickness 0.15)
				)
				(justify left bottom)
				(hide yes)
			)
		)
		(property "License" "Apache-2.0"
			(at 177.8 193.04 0)
			(effects
				(font
					(size 1.27 1.27)
					(thickness 0.15)
				)
				(justify left bottom)
				(hide yes)
			)
		)
		(pin "1"
		)
		(instances
			(project "OCuLink to 10GbE adapter"
				(path ""
					(reference "#PWR096")
					(unit 1)
				)
			)
			(project "thunderbolt-to-10gbe-adapter"
				(path ""
					(reference "#PWR0394")
					(unit 1)
				)
			)
		)
	)
	(symbol
		(lib_id "antmicroResistors0402:R_10R_0402")
		(at 191.77 167.64 0)
		(unit 1)
		(exclude_from_sim no)
		(in_bom yes)
		(on_board yes)
		(dnp no)
		(property "Reference" "R164"
			(at 191.77 166.37 0)
			(effects
				(font
					(size 1.27 1.27)
					(thickness 0.15)
				)
				(justify right)
			)
		)
		(property "Value" "R_10R_0402"
			(at 212.09 180.34 0)
			(effects
				(font
					(size 1.27 1.27)
					(thickness 0.15)
				)
				(justify left bottom)
				(hide yes)
			)
		)
		(property "Footprint" "antmicro-footprints:R_0402_1005Metric"
			(at 212.09 182.88 0)
			(effects
				(font
					(size 1.27 1.27)
					(thickness 0.15)
				)
				(justify left bottom)
				(hide yes)
			)
		)
		(property "Datasheet" "https://www.bourns.com/docs/product-datasheets/cr.pdf"
			(at 212.09 185.42 0)
			(effects
				(font
					(size 1.27 1.27)
					(thickness 0.15)
				)
				(justify left bottom)
				(hide yes)
			)
		)
		(property "Description" "SMD Chip Resistor, 10 ohm, ± 1%, 62.5 mW, 0402 [1005 Metric], Thick Film, General Purpose"
			(at 191.77 167.64 0)
			(effects
				(font
					(size 1.27 1.27)
				)
				(hide yes)
			)
		)
		(property "MPN" "CR0402-FX-10R0GLF"
			(at 212.09 187.96 0)
			(effects
				(font
					(size 1.27 1.27)
					(thickness 0.15)
				)
				(justify left bottom)
				(hide yes)
			)
		)
		(property "Manufacturer" "Bourns"
			(at 212.09 190.5 0)
			(effects
				(font
					(size 1.27 1.27)
					(thickness 0.15)
				)
				(justify left bottom)
				(hide yes)
			)
		)
		(property "License" "Apache-2.0"
			(at 212.09 193.04 0)
			(effects
				(font
					(size 1.27 1.27)
					(thickness 0.15)
				)
				(justify left bottom)
				(hide yes)
			)
		)
		(property "Author" "Antmicro"
			(at 212.09 195.58 0)
			(effects
				(font
					(size 1.27 1.27)
					(thickness 0.15)
				)
				(justify left bottom)
				(hide yes)
			)
		)
		(property "Val" "10R"
			(at 196.85 166.37 0)
			(effects
				(font
					(size 1.27 1.27)
					(thickness 0.15)
				)
				(justify left)
			)
		)
		(property "Tolerance" "1%"
			(at 212.09 177.8 0)
			(effects
				(font
					(size 1.27 1.27)
				)
				(justify left bottom)
				(hide yes)
			)
		)
		(pin "1"
		)
		(pin "2"
		)
		(instances
			(project "OCuLink to 10GbE adapter"
				(path ""
					(reference "R47")
					(unit 1)
				)
			)
			(project "thunderbolt-to-10gbe-adapter"
				(path ""
					(reference "R164")
					(unit 1)
				)
			)
		)
	)
	(symbol
		(lib_id "antmicroResistors0402:R_100R_0402")
		(at 195.58 137.16 90)
		(unit 1)
		(exclude_from_sim no)
		(in_bom yes)
		(on_board yes)
		(dnp yes)
		(property "Reference" "R171"
			(at 197.104 133.35 90)
			(effects
				(font
					(size 1.27 1.27)
					(thickness 0.15)
				)
				(justify right)
			)
		)
		(property "Value" "R_100R_0402"
			(at 208.28 116.84 0)
			(effects
				(font
					(size 1.27 1.27)
					(thickness 0.15)
				)
				(justify left bottom)
				(hide yes)
			)
		)
		(property "Footprint" "antmicro-footprints:R_0402_1005Metric"
			(at 210.82 116.84 0)
			(effects
				(font
					(size 1.27 1.27)
					(thickness 0.15)
				)
				(justify left bottom)
				(hide yes)
			)
		)
		(property "Datasheet" "https://www.bourns.com/docs/product-datasheets/cr.pdf"
			(at 213.36 116.84 0)
			(effects
				(font
					(size 1.27 1.27)
					(thickness 0.15)
				)
				(justify left bottom)
				(hide yes)
			)
		)
		(property "Description" "SMD Chip Resistor, 100 ohm, ± 1%, 62.5 mW, 0402 [1005 Metric], Thick Film, General Purpose"
			(at 195.58 137.16 0)
			(effects
				(font
					(size 1.27 1.27)
				)
				(hide yes)
			)
		)
		(property "MPN" "CR0402-FX-1000GLF"
			(at 215.9 116.84 0)
			(effects
				(font
					(size 1.27 1.27)
					(thickness 0.15)
				)
				(justify left bottom)
				(hide yes)
			)
		)
		(property "Manufacturer" "Bourns"
			(at 218.44 116.84 0)
			(effects
				(font
					(size 1.27 1.27)
					(thickness 0.15)
				)
				(justify left bottom)
				(hide yes)
			)
		)
		(property "License" "Apache-2.0"
			(at 220.98 116.84 0)
			(effects
				(font
					(size 1.27 1.27)
					(thickness 0.15)
				)
				(justify left bottom)
				(hide yes)
			)
		)
		(property "Author" "Antmicro"
			(at 223.52 116.84 0)
			(effects
				(font
					(size 1.27 1.27)
					(thickness 0.15)
				)
				(justify left bottom)
				(hide yes)
			)
		)
		(property "Val" "100R"
			(at 197.104 135.89 90)
			(effects
				(font
					(size 1.27 1.27)
					(thickness 0.15)
				)
				(justify right)
			)
		)
		(property "Tolerance" "1%"
			(at 205.74 116.84 0)
			(effects
				(font
					(size 1.27 1.27)
				)
				(justify left bottom)
				(hide yes)
			)
		)
		(pin "2"
		)
		(pin "1"
		)
		(instances
			(project ""
				(path ""
					(reference "R109")
					(unit 1)
				)
			)
			(project "thunderbolt-to-10gbe-adapter"
				(path ""
					(reference "R171")
					(unit 1)
				)
			)
		)
	)
	(symbol
		(lib_id "antmicropower:+3V3")
		(at 73.66 110.49 0)
		(unit 1)
		(exclude_from_sim no)
		(in_bom yes)
		(on_board yes)
		(dnp no)
		(property "Reference" "#PWR0372"
			(at 88.9 110.49 0)
			(effects
				(font
					(size 1.27 1.27)
					(thickness 0.15)
				)
				(justify left bottom)
				(hide yes)
			)
		)
		(property "Value" "+3V3"
			(at 73.66 106.68 0)
			(effects
				(font
					(size 1.27 1.27)
					(thickness 0.15)
				)
			)
		)
		(property "Footprint" ""
			(at 88.9 118.11 0)
			(effects
				(font
					(size 1.27 1.27)
					(thickness 0.15)
				)
				(justify left bottom)
				(hide yes)
			)
		)
		(property "Datasheet" ""
			(at 88.9 120.65 0)
			(effects
				(font
					(size 1.27 1.27)
					(thickness 0.15)
				)
				(justify left bottom)
				(hide yes)
			)
		)
		(property "Description" ""
			(at 73.66 110.49 0)
			(effects
				(font
					(size 1.27 1.27)
				)
				(hide yes)
			)
		)
		(property "Author" "Antmicro"
			(at 88.9 113.03 0)
			(effects
				(font
					(size 1.27 1.27)
					(thickness 0.15)
				)
				(justify left bottom)
				(hide yes)
			)
		)
		(property "License" "Apache-2.0"
			(at 88.9 115.57 0)
			(effects
				(font
					(size 1.27 1.27)
					(thickness 0.15)
				)
				(justify left bottom)
				(hide yes)
			)
		)
		(pin "1"
		)
		(instances
			(project "OCuLink to 10GbE adapter"
				(path ""
					(reference "#PWR0265")
					(unit 1)
				)
			)
			(project "thunderbolt-to-10gbe-adapter"
				(path ""
					(reference "#PWR0372")
					(unit 1)
				)
			)
		)
	)
	(symbol
		(lib_id "antmicroTestPoints:TP_0.75mm_SMD")
		(at 210.82 233.68 180)
		(unit 1)
		(exclude_from_sim no)
		(in_bom no)
		(on_board yes)
		(dnp no)
		(property "Reference" "TP31"
			(at 206.502 233.68 0)
			(effects
				(font
					(size 1.27 1.27)
					(thickness 0.15)
				)
				(justify left)
			)
		)
		(property "Value" "TP_0.75mm_SMD"
			(at 200.66 229.87 0)
			(effects
				(font
					(size 1.27 1.27)
					(thickness 0.15)
				)
				(justify left bottom)
				(hide yes)
			)
		)
		(property "Footprint" "antmicro-footprints:TP_SMD_0.75mm"
			(at 200.66 227.33 0)
			(effects
				(font
					(size 1.27 1.27)
					(thickness 0.15)
				)
				(justify left bottom)
				(hide yes)
			)
		)
		(property "Datasheet" ""
			(at 193.04 220.98 0)
			(effects
				(font
					(size 1.27 1.27)
					(thickness 0.15)
				)
				(justify left bottom)
				(hide yes)
			)
		)
		(property "Description" "SMT test point"
			(at 210.82 233.68 0)
			(effects
				(font
					(size 1.27 1.27)
				)
				(hide yes)
			)
		)
		(property "MPN" ""
			(at 200.025 222.25 0)
			(effects
				(font
					(size 1.27 1.27)
					(thickness 0.15)
				)
				(justify left bottom)
				(hide yes)
			)
		)
		(property "Manufacturer" ""
			(at 200.025 227.33 0)
			(effects
				(font
					(size 1.27 1.27)
					(thickness 0.15)
				)
				(justify left bottom)
				(hide yes)
			)
		)
		(property "Author" "Antmicro"
			(at 200.66 224.79 0)
			(effects
				(font
					(size 1.27 1.27)
					(thickness 0.15)
				)
				(justify left bottom)
				(hide yes)
			)
		)
		(property "License" "Apache-2.0"
			(at 200.66 222.25 0)
			(effects
				(font
					(size 1.27 1.27)
					(thickness 0.15)
				)
				(justify left bottom)
				(hide yes)
			)
		)
		(pin "1"
		)
		(instances
			(project ""
				(path ""
					(reference "TP10")
					(unit 1)
				)
			)
			(project "thunderbolt-to-10gbe-adapter"
				(path ""
					(reference "TP31")
					(unit 1)
				)
			)
		)
	)
	(symbol
		(lib_id "antmicropower:GND")
		(at 137.16 231.14 0)
		(mirror y)
		(unit 1)
		(exclude_from_sim no)
		(in_bom yes)
		(on_board yes)
		(dnp no)
		(property "Reference" "#PWR0383"
			(at 128.27 233.68 0)
			(effects
				(font
					(size 1.27 1.27)
					(thickness 0.15)
				)
				(justify left bottom)
				(hide yes)
			)
		)
		(property "Value" "GND"
			(at 137.16 234.95 0)
			(effects
				(font
					(size 1.27 1.27)
					(thickness 0.15)
				)
			)
		)
		(property "Footprint" ""
			(at 128.27 238.76 0)
			(effects
				(font
					(size 1.27 1.27)
					(thickness 0.15)
				)
				(justify left bottom)
				(hide yes)
			)
		)
		(property "Datasheet" ""
			(at 128.27 243.84 0)
			(effects
				(font
					(size 1.27 1.27)
					(thickness 0.15)
				)
				(justify left bottom)
				(hide yes)
			)
		)
		(property "Description" ""
			(at 137.16 231.14 0)
			(effects
				(font
					(size 1.27 1.27)
				)
				(hide yes)
			)
		)
		(property "Author" "Antmicro"
			(at 128.27 238.76 0)
			(effects
				(font
					(size 1.27 1.27)
					(thickness 0.15)
				)
				(justify left bottom)
				(hide yes)
			)
		)
		(property "License" "Apache-2.0"
			(at 128.27 241.3 0)
			(effects
				(font
					(size 1.27 1.27)
					(thickness 0.15)
				)
				(justify left bottom)
				(hide yes)
			)
		)
		(pin "1"
		)
		(instances
			(project "OCuLink to 10GbE adapter"
				(path ""
					(reference "#PWR0101")
					(unit 1)
				)
			)
			(project "thunderbolt-to-10gbe-adapter"
				(path ""
					(reference "#PWR0383")
					(unit 1)
				)
			)
		)
	)
	(symbol
		(lib_id "antmicropower:GND")
		(at 163.83 254 0)
		(unit 1)
		(exclude_from_sim no)
		(in_bom yes)
		(on_board yes)
		(dnp no)
		(property "Reference" "#PWR0392"
			(at 172.72 256.54 0)
			(effects
				(font
					(size 1.27 1.27)
					(thickness 0.15)
				)
				(justify left bottom)
				(hide yes)
			)
		)
		(property "Value" "GND"
			(at 163.83 257.81 0)
			(effects
				(font
					(size 1.27 1.27)
					(thickness 0.15)
				)
			)
		)
		(property "Footprint" ""
			(at 172.72 261.62 0)
			(effects
				(font
					(size 1.27 1.27)
					(thickness 0.15)
				)
				(justify left bottom)
				(hide yes)
			)
		)
		(property "Datasheet" ""
			(at 172.72 266.7 0)
			(effects
				(font
					(size 1.27 1.27)
					(thickness 0.15)
				)
				(justify left bottom)
				(hide yes)
			)
		)
		(property "Description" ""
			(at 163.83 254 0)
			(effects
				(font
					(size 1.27 1.27)
				)
				(hide yes)
			)
		)
		(property "Author" "Antmicro"
			(at 172.72 261.62 0)
			(effects
				(font
					(size 1.27 1.27)
					(thickness 0.15)
				)
				(justify left bottom)
				(hide yes)
			)
		)
		(property "License" "Apache-2.0"
			(at 172.72 264.16 0)
			(effects
				(font
					(size 1.27 1.27)
					(thickness 0.15)
				)
				(justify left bottom)
				(hide yes)
			)
		)
		(pin "1"
		)
		(instances
			(project "OCuLink to 10GbE adapter"
				(path ""
					(reference "#PWR0279")
					(unit 1)
				)
			)
			(project "thunderbolt-to-10gbe-adapter"
				(path ""
					(reference "#PWR0392")
					(unit 1)
				)
			)
		)
	)
	(symbol
		(lib_id "antmicroTestPoints:TP_0.75mm_SMD")
		(at 322.58 109.22 0)
		(unit 1)
		(exclude_from_sim no)
		(in_bom no)
		(on_board yes)
		(dnp no)
		(fields_autoplaced yes)
		(property "Reference" "TP35"
			(at 327.66 109.22 0)
			(effects
				(font
					(size 1.27 1.27)
					(thickness 0.15)
				)
				(justify left)
			)
		)
		(property "Value" "TP_0.75mm_SMD"
			(at 332.74 113.03 0)
			(effects
				(font
					(size 1.27 1.27)
					(thickness 0.15)
				)
				(justify left bottom)
				(hide yes)
			)
		)
		(property "Footprint" "antmicro-footprints:TP_SMD_0.75mm"
			(at 332.74 115.57 0)
			(effects
				(font
					(size 1.27 1.27)
					(thickness 0.15)
				)
				(justify left bottom)
				(hide yes)
			)
		)
		(property "Datasheet" ""
			(at 340.36 121.92 0)
			(effects
				(font
					(size 1.27 1.27)
					(thickness 0.15)
				)
				(justify left bottom)
				(hide yes)
			)
		)
		(property "Description" "SMT test point"
			(at 333.375 123.19 0)
			(effects
				(font
					(size 1.27 1.27)
				)
				(justify left bottom)
				(hide yes)
			)
		)
		(property "MPN" ""
			(at 333.375 120.65 0)
			(effects
				(font
					(size 1.27 1.27)
					(thickness 0.15)
				)
				(justify left bottom)
				(hide yes)
			)
		)
		(property "Manufacturer" ""
			(at 333.375 115.57 0)
			(effects
				(font
					(size 1.27 1.27)
					(thickness 0.15)
				)
				(justify left bottom)
				(hide yes)
			)
		)
		(property "Author" "Antmicro"
			(at 332.74 118.11 0)
			(effects
				(font
					(size 1.27 1.27)
					(thickness 0.15)
				)
				(justify left bottom)
				(hide yes)
			)
		)
		(property "License" "Apache-2.0"
			(at 332.74 120.65 0)
			(effects
				(font
					(size 1.27 1.27)
					(thickness 0.15)
				)
				(justify left bottom)
				(hide yes)
			)
		)
		(pin "1"
		)
		(instances
			(project "thunderbolt-to-10gbe-adapter"
				(path ""
					(reference "TP35")
					(unit 1)
				)
			)
		)
	)
	(symbol
		(lib_id "antmicroResistors0402:R_10k_0402")
		(at 297.18 104.14 90)
		(unit 1)
		(exclude_from_sim no)
		(in_bom yes)
		(on_board yes)
		(dnp no)
		(property "Reference" "R179"
			(at 298.704 100.33 90)
			(effects
				(font
					(size 1.27 1.27)
					(thickness 0.15)
				)
				(justify right)
			)
		)
		(property "Value" "R_10k_0402"
			(at 309.88 83.82 0)
			(effects
				(font
					(size 1.27 1.27)
					(thickness 0.15)
				)
				(justify left bottom)
				(hide yes)
			)
		)
		(property "Footprint" "antmicro-footprints:R_0402_1005Metric"
			(at 312.42 83.82 0)
			(effects
				(font
					(size 1.27 1.27)
					(thickness 0.15)
				)
				(justify left bottom)
				(hide yes)
			)
		)
		(property "Datasheet" "https://www.bourns.com/docs/product-datasheets/cr.pdf"
			(at 314.96 83.82 0)
			(effects
				(font
					(size 1.27 1.27)
					(thickness 0.15)
				)
				(justify left bottom)
				(hide yes)
			)
		)
		(property "Description" "SMD Chip Resistor, 10 kohm, ± 1%, 62.5 mW, 0402 [1005 Metric], Thick Film, General Purpose"
			(at 297.18 104.14 0)
			(effects
				(font
					(size 1.27 1.27)
				)
				(hide yes)
			)
		)
		(property "MPN" "CR0402-FX-1002GLF"
			(at 317.5 83.82 0)
			(effects
				(font
					(size 1.27 1.27)
					(thickness 0.15)
				)
				(justify left bottom)
				(hide yes)
			)
		)
		(property "Manufacturer" "Bourns"
			(at 320.04 83.82 0)
			(effects
				(font
					(size 1.27 1.27)
					(thickness 0.15)
				)
				(justify left bottom)
				(hide yes)
			)
		)
		(property "License" "Apache-2.0"
			(at 322.58 83.82 0)
			(effects
				(font
					(size 1.27 1.27)
					(thickness 0.15)
				)
				(justify left bottom)
				(hide yes)
			)
		)
		(property "Author" "Antmicro"
			(at 325.12 83.82 0)
			(effects
				(font
					(size 1.27 1.27)
					(thickness 0.15)
				)
				(justify left bottom)
				(hide yes)
			)
		)
		(property "Val" "10k"
			(at 298.704 102.87 90)
			(effects
				(font
					(size 1.27 1.27)
					(thickness 0.15)
				)
				(justify right)
			)
		)
		(property "Tolerance" "1%"
			(at 307.34 83.82 0)
			(effects
				(font
					(size 1.27 1.27)
				)
				(justify left bottom)
				(hide yes)
			)
		)
		(pin "2"
		)
		(pin "1"
		)
		(instances
			(project "OCuLink to 10GbE adapter"
				(path ""
					(reference "R92")
					(unit 1)
				)
			)
			(project "thunderbolt-to-10gbe-adapter"
				(path ""
					(reference "R179")
					(unit 1)
				)
			)
		)
	)
	(symbol
		(lib_id "antmicroResistors0402:R_1k_0402")
		(at 308.61 212.09 90)
		(unit 1)
		(exclude_from_sim no)
		(in_bom yes)
		(on_board yes)
		(dnp no)
		(property "Reference" "R181"
			(at 310.134 208.28 90)
			(effects
				(font
					(size 1.27 1.27)
					(thickness 0.15)
				)
				(justify right)
			)
		)
		(property "Value" "R_1k_0402"
			(at 321.31 191.77 0)
			(effects
				(font
					(size 1.27 1.27)
					(thickness 0.15)
				)
				(justify left bottom)
				(hide yes)
			)
		)
		(property "Footprint" "antmicro-footprints:R_0402_1005Metric"
			(at 323.85 191.77 0)
			(effects
				(font
					(size 1.27 1.27)
					(thickness 0.15)
				)
				(justify left bottom)
				(hide yes)
			)
		)
		(property "Datasheet" "https://www.bourns.com/docs/product-datasheets/cr.pdf"
			(at 326.39 191.77 0)
			(effects
				(font
					(size 1.27 1.27)
					(thickness 0.15)
				)
				(justify left bottom)
				(hide yes)
			)
		)
		(property "Description" "SMD Chip Resistor, 1 kohm, ± 1%, 63 mW, 0402 [1005 Metric], Thick Film, General Purpose"
			(at 308.61 212.09 0)
			(effects
				(font
					(size 1.27 1.27)
				)
				(hide yes)
			)
		)
		(property "MPN" "CR0402-FX-1001GLF"
			(at 328.93 191.77 0)
			(effects
				(font
					(size 1.27 1.27)
					(thickness 0.15)
				)
				(justify left bottom)
				(hide yes)
			)
		)
		(property "Manufacturer" "Bourns"
			(at 331.47 191.77 0)
			(effects
				(font
					(size 1.27 1.27)
					(thickness 0.15)
				)
				(justify left bottom)
				(hide yes)
			)
		)
		(property "License" "Apache-2.0"
			(at 334.01 191.77 0)
			(effects
				(font
					(size 1.27 1.27)
					(thickness 0.15)
				)
				(justify left bottom)
				(hide yes)
			)
		)
		(property "Author" "Antmicro"
			(at 336.55 191.77 0)
			(effects
				(font
					(size 1.27 1.27)
					(thickness 0.15)
				)
				(justify left bottom)
				(hide yes)
			)
		)
		(property "Val" "1k"
			(at 310.134 210.82 90)
			(effects
				(font
					(size 1.27 1.27)
					(thickness 0.15)
				)
				(justify right)
			)
		)
		(property "Tolerance" "1%"
			(at 318.77 191.77 0)
			(effects
				(font
					(size 1.27 1.27)
				)
				(justify left bottom)
				(hide yes)
			)
		)
		(pin "2"
		)
		(pin "1"
		)
		(instances
			(project "OCuLink to 10GbE adapter"
				(path ""
					(reference "R117")
					(unit 1)
				)
			)
			(project "thunderbolt-to-10gbe-adapter"
				(path ""
					(reference "R181")
					(unit 1)
				)
			)
		)
	)
	(symbol
		(lib_id "antmicroCapacitors0402:C_5p6_0402")
		(at 168.91 180.34 90)
		(unit 1)
		(exclude_from_sim no)
		(in_bom yes)
		(on_board yes)
		(dnp no)
		(property "Reference" "C280"
			(at 170.942 176.53 90)
			(effects
				(font
					(size 1.27 1.27)
					(thickness 0.15)
				)
				(justify right)
			)
		)
		(property "Value" "C_5p6_0402"
			(at 179.07 160.02 0)
			(effects
				(font
					(size 1.27 1.27)
					(thickness 0.15)
				)
				(justify left bottom)
				(hide yes)
			)
		)
		(property "Footprint" "antmicro-footprints:C_0402_1005Metric"
			(at 181.61 160.02 0)
			(effects
				(font
					(size 1.27 1.27)
					(thickness 0.15)
				)
				(justify left bottom)
				(hide yes)
			)
		)
		(property "Datasheet" "https://www.mouser.com/datasheet/3/76/2/GCM1555C1H5R6BA16_01A.pdf"
			(at 184.15 160.02 0)
			(effects
				(font
					(size 1.27 1.27)
					(thickness 0.15)
				)
				(justify left bottom)
				(hide yes)
			)
		)
		(property "Description" "Multilayer Ceramic Capacitors MLCC - SMD/SMT 5.6 pF 50 VDC 0.1 pF 0402 C0G (NP0) AEC-Q200"
			(at 168.91 180.34 0)
			(effects
				(font
					(size 1.27 1.27)
				)
				(hide yes)
			)
		)
		(property "MPN" "GCM1555C1H5R6BA16D"
			(at 186.69 160.02 0)
			(effects
				(font
					(size 1.27 1.27)
					(thickness 0.15)
				)
				(justify left bottom)
				(hide yes)
			)
		)
		(property "Manufacturer" "Murata"
			(at 189.23 160.02 0)
			(effects
				(font
					(size 1.27 1.27)
					(thickness 0.15)
				)
				(justify left bottom)
				(hide yes)
			)
		)
		(property "License" "Apache-2.0"
			(at 191.77 160.02 0)
			(effects
				(font
					(size 1.27 1.27)
					(thickness 0.15)
				)
				(justify left bottom)
				(hide yes)
			)
		)
		(property "Author" "Antmicro"
			(at 194.31 160.02 0)
			(effects
				(font
					(size 1.27 1.27)
					(thickness 0.15)
				)
				(justify left bottom)
				(hide yes)
			)
		)
		(property "Val" "5p6"
			(at 170.942 179.07 90)
			(effects
				(font
					(size 1.27 1.27)
					(thickness 0.15)
				)
				(justify right)
			)
		)
		(property "Voltage" "50V"
			(at 196.85 160.02 0)
			(effects
				(font
					(size 1.27 1.27)
				)
				(justify left bottom)
				(hide yes)
			)
		)
		(property "Dielectric" "C0G"
			(at 199.39 160.02 0)
			(effects
				(font
					(size 1.27 1.27)
				)
				(justify left bottom)
				(hide yes)
			)
		)
		(pin "2"
		)
		(pin "1"
		)
		(instances
			(project "OCuLink to 10GbE adapter"
				(path ""
					(reference "C72")
					(unit 1)
				)
			)
			(project "thunderbolt-to-10gbe-adapter"
				(path ""
					(reference "C280")
					(unit 1)
				)
			)
		)
	)
	(symbol
		(lib_id "antmicroResistors0402:R_100k_0402")
		(at 171.45 86.36 90)
		(unit 1)
		(exclude_from_sim no)
		(in_bom yes)
		(on_board yes)
		(dnp no)
		(property "Reference" "R152"
			(at 172.974 82.55 90)
			(effects
				(font
					(size 1.27 1.27)
					(thickness 0.15)
				)
				(justify right)
			)
		)
		(property "Value" "R_100k_0402"
			(at 184.15 66.04 0)
			(effects
				(font
					(size 1.27 1.27)
					(thickness 0.15)
				)
				(justify left bottom)
				(hide yes)
			)
		)
		(property "Footprint" "antmicro-footprints:R_0402_1005Metric"
			(at 186.69 66.04 0)
			(effects
				(font
					(size 1.27 1.27)
					(thickness 0.15)
				)
				(justify left bottom)
				(hide yes)
			)
		)
		(property "Datasheet" "https://www.bourns.com/docs/product-datasheets/cr.pdf"
			(at 189.23 66.04 0)
			(effects
				(font
					(size 1.27 1.27)
					(thickness 0.15)
				)
				(justify left bottom)
				(hide yes)
			)
		)
		(property "Description" "SMD Chip Resistor, 100 kohm, ± 1%, 62.5 mW, 0402 [1005 Metric], Thick Film, General Purpose"
			(at 171.45 86.36 0)
			(effects
				(font
					(size 1.27 1.27)
				)
				(hide yes)
			)
		)
		(property "MPN" "CR0402-FX-1003GLF"
			(at 191.77 66.04 0)
			(effects
				(font
					(size 1.27 1.27)
					(thickness 0.15)
				)
				(justify left bottom)
				(hide yes)
			)
		)
		(property "Manufacturer" "Bourns"
			(at 194.31 66.04 0)
			(effects
				(font
					(size 1.27 1.27)
					(thickness 0.15)
				)
				(justify left bottom)
				(hide yes)
			)
		)
		(property "License" "Apache-2.0"
			(at 196.85 66.04 0)
			(effects
				(font
					(size 1.27 1.27)
					(thickness 0.15)
				)
				(justify left bottom)
				(hide yes)
			)
		)
		(property "Author" "Antmicro"
			(at 199.39 66.04 0)
			(effects
				(font
					(size 1.27 1.27)
					(thickness 0.15)
				)
				(justify left bottom)
				(hide yes)
			)
		)
		(property "Val" "100k"
			(at 172.974 85.09 90)
			(effects
				(font
					(size 1.27 1.27)
					(thickness 0.15)
				)
				(justify right)
			)
		)
		(property "Tolerance" "1%"
			(at 181.61 66.04 0)
			(effects
				(font
					(size 1.27 1.27)
				)
				(justify left bottom)
				(hide yes)
			)
		)
		(pin "2"
		)
		(pin "1"
		)
		(instances
			(project "OCuLink to 10GbE adapter"
				(path ""
					(reference "R88")
					(unit 1)
				)
			)
			(project "thunderbolt-to-10gbe-adapter"
				(path ""
					(reference "R152")
					(unit 1)
				)
			)
		)
	)
	(symbol
		(lib_id "antmicroTestPoints:TP_0.75mm_SMD")
		(at 133.35 58.42 180)
		(unit 1)
		(exclude_from_sim no)
		(in_bom no)
		(on_board yes)
		(dnp no)
		(property "Reference" "TP21"
			(at 129.032 58.42 0)
			(effects
				(font
					(size 1.27 1.27)
					(thickness 0.15)
				)
				(justify left)
			)
		)
		(property "Value" "TP_0.75mm_SMD"
			(at 123.19 54.61 0)
			(effects
				(font
					(size 1.27 1.27)
					(thickness 0.15)
				)
				(justify left bottom)
				(hide yes)
			)
		)
		(property "Footprint" "antmicro-footprints:TP_SMD_0.75mm"
			(at 123.19 52.07 0)
			(effects
				(font
					(size 1.27 1.27)
					(thickness 0.15)
				)
				(justify left bottom)
				(hide yes)
			)
		)
		(property "Datasheet" ""
			(at 115.57 45.72 0)
			(effects
				(font
					(size 1.27 1.27)
					(thickness 0.15)
				)
				(justify left bottom)
				(hide yes)
			)
		)
		(property "Description" "SMT test point"
			(at 133.35 58.42 0)
			(effects
				(font
					(size 1.27 1.27)
				)
				(hide yes)
			)
		)
		(property "MPN" ""
			(at 122.555 46.99 0)
			(effects
				(font
					(size 1.27 1.27)
					(thickness 0.15)
				)
				(justify left bottom)
				(hide yes)
			)
		)
		(property "Manufacturer" ""
			(at 122.555 52.07 0)
			(effects
				(font
					(size 1.27 1.27)
					(thickness 0.15)
				)
				(justify left bottom)
				(hide yes)
			)
		)
		(property "Author" "Antmicro"
			(at 123.19 49.53 0)
			(effects
				(font
					(size 1.27 1.27)
					(thickness 0.15)
				)
				(justify left bottom)
				(hide yes)
			)
		)
		(property "License" "Apache-2.0"
			(at 123.19 46.99 0)
			(effects
				(font
					(size 1.27 1.27)
					(thickness 0.15)
				)
				(justify left bottom)
				(hide yes)
			)
		)
		(pin "1"
		)
		(instances
			(project ""
				(path ""
					(reference "TP1")
					(unit 1)
				)
			)
			(project "thunderbolt-to-10gbe-adapter"
				(path ""
					(reference "TP21")
					(unit 1)
				)
			)
		)
	)
	(symbol
		(lib_id "antmicroTestPoints:TP_0.75mm_SMD")
		(at 208.28 175.26 180)
		(unit 1)
		(exclude_from_sim no)
		(in_bom no)
		(on_board yes)
		(dnp no)
		(property "Reference" "TP30"
			(at 203.962 175.26 0)
			(effects
				(font
					(size 1.27 1.27)
					(thickness 0.15)
				)
				(justify left)
			)
		)
		(property "Value" "TP_0.75mm_SMD"
			(at 198.12 171.45 0)
			(effects
				(font
					(size 1.27 1.27)
					(thickness 0.15)
				)
				(justify left bottom)
				(hide yes)
			)
		)
		(property "Footprint" "antmicro-footprints:TP_SMD_0.75mm"
			(at 198.12 168.91 0)
			(effects
				(font
					(size 1.27 1.27)
					(thickness 0.15)
				)
				(justify left bottom)
				(hide yes)
			)
		)
		(property "Datasheet" ""
			(at 190.5 162.56 0)
			(effects
				(font
					(size 1.27 1.27)
					(thickness 0.15)
				)
				(justify left bottom)
				(hide yes)
			)
		)
		(property "Description" "SMT test point"
			(at 208.28 175.26 0)
			(effects
				(font
					(size 1.27 1.27)
				)
				(hide yes)
			)
		)
		(property "MPN" ""
			(at 197.485 163.83 0)
			(effects
				(font
					(size 1.27 1.27)
					(thickness 0.15)
				)
				(justify left bottom)
				(hide yes)
			)
		)
		(property "Manufacturer" ""
			(at 197.485 168.91 0)
			(effects
				(font
					(size 1.27 1.27)
					(thickness 0.15)
				)
				(justify left bottom)
				(hide yes)
			)
		)
		(property "Author" "Antmicro"
			(at 198.12 166.37 0)
			(effects
				(font
					(size 1.27 1.27)
					(thickness 0.15)
				)
				(justify left bottom)
				(hide yes)
			)
		)
		(property "License" "Apache-2.0"
			(at 198.12 163.83 0)
			(effects
				(font
					(size 1.27 1.27)
					(thickness 0.15)
				)
				(justify left bottom)
				(hide yes)
			)
		)
		(pin "1"
		)
		(instances
			(project "OCuLink to 10GbE adapter"
				(path ""
					(reference "TP25")
					(unit 1)
				)
			)
			(project "thunderbolt-to-10gbe-adapter"
				(path ""
					(reference "TP30")
					(unit 1)
				)
			)
		)
	)
	(symbol
		(lib_id "antmicroCapacitors0402:C_100n_0402")
		(at 138.43 186.69 90)
		(unit 1)
		(exclude_from_sim no)
		(in_bom yes)
		(on_board yes)
		(dnp no)
		(property "Reference" "C278"
			(at 140.462 182.88 90)
			(effects
				(font
					(size 1.27 1.27)
					(thickness 0.15)
				)
				(justify right)
			)
		)
		(property "Value" "C_100n_0402"
			(at 161.29 171.45 0)
			(effects
				(font
					(size 1.27 1.27)
					(thickness 0.15)
				)
				(justify left bottom)
				(hide yes)
			)
		)
		(property "Footprint" "antmicro-footprints:C_0402_1005Metric"
			(at 163.83 171.45 0)
			(effects
				(font
					(size 1.27 1.27)
					(thickness 0.15)
				)
				(justify left bottom)
				(hide yes)
			)
		)
		(property "Datasheet" "https://www.murata.com/products/productdetail?partno=GRM155R61H104KE14%23"
			(at 166.37 171.45 0)
			(effects
				(font
					(size 1.27 1.27)
					(thickness 0.15)
				)
				(justify left bottom)
				(hide yes)
			)
		)
		(property "Description" "SMD Multilayer Ceramic Capacitor, 0.1 µF, 50 V, 0402 [1005 Metric], ± 10%, X5R, GRM Series"
			(at 138.43 186.69 0)
			(effects
				(font
					(size 1.27 1.27)
				)
				(hide yes)
			)
		)
		(property "MPN" "GRM155R61H104KE14D"
			(at 168.91 171.45 0)
			(effects
				(font
					(size 1.27 1.27)
					(thickness 0.15)
				)
				(justify left bottom)
				(hide yes)
			)
		)
		(property "Val" "100n"
			(at 140.462 185.42 90)
			(effects
				(font
					(size 1.27 1.27)
					(thickness 0.15)
				)
				(justify right)
			)
		)
		(property "Voltage" "50V"
			(at 148.59 171.45 0)
			(effects
				(font
					(size 1.27 1.27)
					(thickness 0.15)
				)
				(justify left bottom)
				(hide yes)
			)
		)
		(property "Dielectric" "X5R"
			(at 151.13 171.45 0)
			(effects
				(font
					(size 1.27 1.27)
					(thickness 0.15)
				)
				(justify left bottom)
				(hide yes)
			)
		)
		(property "Manufacturer" "Murata"
			(at 153.67 171.45 0)
			(effects
				(font
					(size 1.27 1.27)
					(thickness 0.15)
				)
				(justify left bottom)
				(hide yes)
			)
		)
		(property "License" "Apache-2.0"
			(at 156.21 171.45 0)
			(effects
				(font
					(size 1.27 1.27)
					(thickness 0.15)
				)
				(justify left bottom)
				(hide yes)
			)
		)
		(property "Author" "Antmicro"
			(at 158.75 171.45 0)
			(effects
				(font
					(size 1.27 1.27)
					(thickness 0.15)
				)
				(justify left bottom)
				(hide yes)
			)
		)
		(pin "2"
		)
		(pin "1"
		)
		(instances
			(project "OCuLink to 10GbE adapter"
				(path ""
					(reference "C76")
					(unit 1)
				)
			)
			(project "thunderbolt-to-10gbe-adapter"
				(path ""
					(reference "C278")
					(unit 1)
				)
			)
		)
	)
	(symbol
		(lib_id "antmicropower:GND")
		(at 180.34 88.9 0)
		(unit 1)
		(exclude_from_sim no)
		(in_bom yes)
		(on_board yes)
		(dnp no)
		(property "Reference" "#PWR0399"
			(at 189.23 91.44 0)
			(effects
				(font
					(size 1.27 1.27)
					(thickness 0.15)
				)
				(justify left bottom)
				(hide yes)
			)
		)
		(property "Value" "GND"
			(at 180.34 92.71 0)
			(effects
				(font
					(size 1.27 1.27)
					(thickness 0.15)
				)
			)
		)
		(property "Footprint" ""
			(at 189.23 96.52 0)
			(effects
				(font
					(size 1.27 1.27)
					(thickness 0.15)
				)
				(justify left bottom)
				(hide yes)
			)
		)
		(property "Datasheet" ""
			(at 189.23 101.6 0)
			(effects
				(font
					(size 1.27 1.27)
					(thickness 0.15)
				)
				(justify left bottom)
				(hide yes)
			)
		)
		(property "Description" ""
			(at 180.34 88.9 0)
			(effects
				(font
					(size 1.27 1.27)
				)
				(hide yes)
			)
		)
		(property "Author" "Antmicro"
			(at 189.23 96.52 0)
			(effects
				(font
					(size 1.27 1.27)
					(thickness 0.15)
				)
				(justify left bottom)
				(hide yes)
			)
		)
		(property "License" "Apache-2.0"
			(at 189.23 99.06 0)
			(effects
				(font
					(size 1.27 1.27)
					(thickness 0.15)
				)
				(justify left bottom)
				(hide yes)
			)
		)
		(pin "1"
		)
		(instances
			(project "OCuLink to 10GbE adapter"
				(path ""
					(reference "#PWR0261")
					(unit 1)
				)
			)
			(project "thunderbolt-to-10gbe-adapter"
				(path ""
					(reference "#PWR0399")
					(unit 1)
				)
			)
		)
	)
	(symbol
		(lib_id "antmicroTestPoints:TP_0.75mm_SMD")
		(at 133.35 68.58 180)
		(unit 1)
		(exclude_from_sim no)
		(in_bom no)
		(on_board yes)
		(dnp no)
		(property "Reference" "TP25"
			(at 129.032 68.58 0)
			(effects
				(font
					(size 1.27 1.27)
					(thickness 0.15)
				)
				(justify left)
			)
		)
		(property "Value" "TP_0.75mm_SMD"
			(at 123.19 64.77 0)
			(effects
				(font
					(size 1.27 1.27)
					(thickness 0.15)
				)
				(justify left bottom)
				(hide yes)
			)
		)
		(property "Footprint" "antmicro-footprints:TP_SMD_0.75mm"
			(at 123.19 62.23 0)
			(effects
				(font
					(size 1.27 1.27)
					(thickness 0.15)
				)
				(justify left bottom)
				(hide yes)
			)
		)
		(property "Datasheet" ""
			(at 115.57 55.88 0)
			(effects
				(font
					(size 1.27 1.27)
					(thickness 0.15)
				)
				(justify left bottom)
				(hide yes)
			)
		)
		(property "Description" "SMT test point"
			(at 133.35 68.58 0)
			(effects
				(font
					(size 1.27 1.27)
				)
				(hide yes)
			)
		)
		(property "MPN" ""
			(at 122.555 57.15 0)
			(effects
				(font
					(size 1.27 1.27)
					(thickness 0.15)
				)
				(justify left bottom)
				(hide yes)
			)
		)
		(property "Manufacturer" ""
			(at 122.555 62.23 0)
			(effects
				(font
					(size 1.27 1.27)
					(thickness 0.15)
				)
				(justify left bottom)
				(hide yes)
			)
		)
		(property "Author" "Antmicro"
			(at 123.19 59.69 0)
			(effects
				(font
					(size 1.27 1.27)
					(thickness 0.15)
				)
				(justify left bottom)
				(hide yes)
			)
		)
		(property "License" "Apache-2.0"
			(at 123.19 57.15 0)
			(effects
				(font
					(size 1.27 1.27)
					(thickness 0.15)
				)
				(justify left bottom)
				(hide yes)
			)
		)
		(pin "1"
		)
		(instances
			(project "OCuLink to 10GbE adapter"
				(path ""
					(reference "TP5")
					(unit 1)
				)
			)
			(project "thunderbolt-to-10gbe-adapter"
				(path ""
					(reference "TP25")
					(unit 1)
				)
			)
		)
	)
	(symbol
		(lib_id "antmicroResistors0402:R_100k_0402")
		(at 177.8 55.88 90)
		(unit 1)
		(exclude_from_sim no)
		(in_bom yes)
		(on_board yes)
		(dnp no)
		(property "Reference" "R156"
			(at 179.324 52.07 90)
			(effects
				(font
					(size 1.27 1.27)
					(thickness 0.15)
				)
				(justify right)
			)
		)
		(property "Value" "R_100k_0402"
			(at 190.5 35.56 0)
			(effects
				(font
					(size 1.27 1.27)
					(thickness 0.15)
				)
				(justify left bottom)
				(hide yes)
			)
		)
		(property "Footprint" "antmicro-footprints:R_0402_1005Metric"
			(at 193.04 35.56 0)
			(effects
				(font
					(size 1.27 1.27)
					(thickness 0.15)
				)
				(justify left bottom)
				(hide yes)
			)
		)
		(property "Datasheet" "https://www.bourns.com/docs/product-datasheets/cr.pdf"
			(at 195.58 35.56 0)
			(effects
				(font
					(size 1.27 1.27)
					(thickness 0.15)
				)
				(justify left bottom)
				(hide yes)
			)
		)
		(property "Description" "SMD Chip Resistor, 100 kohm, ± 1%, 62.5 mW, 0402 [1005 Metric], Thick Film, General Purpose"
			(at 177.8 55.88 0)
			(effects
				(font
					(size 1.27 1.27)
				)
				(hide yes)
			)
		)
		(property "MPN" "CR0402-FX-1003GLF"
			(at 198.12 35.56 0)
			(effects
				(font
					(size 1.27 1.27)
					(thickness 0.15)
				)
				(justify left bottom)
				(hide yes)
			)
		)
		(property "Manufacturer" "Bourns"
			(at 200.66 35.56 0)
			(effects
				(font
					(size 1.27 1.27)
					(thickness 0.15)
				)
				(justify left bottom)
				(hide yes)
			)
		)
		(property "License" "Apache-2.0"
			(at 203.2 35.56 0)
			(effects
				(font
					(size 1.27 1.27)
					(thickness 0.15)
				)
				(justify left bottom)
				(hide yes)
			)
		)
		(property "Author" "Antmicro"
			(at 205.74 35.56 0)
			(effects
				(font
					(size 1.27 1.27)
					(thickness 0.15)
				)
				(justify left bottom)
				(hide yes)
			)
		)
		(property "Val" "100k"
			(at 179.324 54.61 90)
			(effects
				(font
					(size 1.27 1.27)
					(thickness 0.15)
				)
				(justify right)
			)
		)
		(property "Tolerance" "1%"
			(at 187.96 35.56 0)
			(effects
				(font
					(size 1.27 1.27)
				)
				(justify left bottom)
				(hide yes)
			)
		)
		(pin "2"
		)
		(pin "1"
		)
		(instances
			(project "OCuLink to 10GbE adapter"
				(path ""
					(reference "R81")
					(unit 1)
				)
			)
			(project "thunderbolt-to-10gbe-adapter"
				(path ""
					(reference "R156")
					(unit 1)
				)
			)
		)
	)
	(symbol
		(lib_id "antmicroResistors0402:R_10k_0402")
		(at 176.53 111.76 90)
		(unit 1)
		(exclude_from_sim no)
		(in_bom yes)
		(on_board yes)
		(dnp no)
		(property "Reference" "R154"
			(at 177.8 107.95 90)
			(effects
				(font
					(size 1.27 1.27)
					(thickness 0.15)
				)
				(justify right)
			)
		)
		(property "Value" "R_10k_0402"
			(at 189.23 91.44 0)
			(effects
				(font
					(size 1.27 1.27)
					(thickness 0.15)
				)
				(justify left bottom)
				(hide yes)
			)
		)
		(property "Footprint" "antmicro-footprints:R_0402_1005Metric"
			(at 191.77 91.44 0)
			(effects
				(font
					(size 1.27 1.27)
					(thickness 0.15)
				)
				(justify left bottom)
				(hide yes)
			)
		)
		(property "Datasheet" "https://www.bourns.com/docs/product-datasheets/cr.pdf"
			(at 194.31 91.44 0)
			(effects
				(font
					(size 1.27 1.27)
					(thickness 0.15)
				)
				(justify left bottom)
				(hide yes)
			)
		)
		(property "Description" "SMD Chip Resistor, 10 kohm, ± 1%, 62.5 mW, 0402 [1005 Metric], Thick Film, General Purpose"
			(at 176.53 111.76 0)
			(effects
				(font
					(size 1.27 1.27)
				)
				(hide yes)
			)
		)
		(property "MPN" "CR0402-FX-1002GLF"
			(at 196.85 91.44 0)
			(effects
				(font
					(size 1.27 1.27)
					(thickness 0.15)
				)
				(justify left bottom)
				(hide yes)
			)
		)
		(property "Manufacturer" "Bourns"
			(at 199.39 91.44 0)
			(effects
				(font
					(size 1.27 1.27)
					(thickness 0.15)
				)
				(justify left bottom)
				(hide yes)
			)
		)
		(property "License" "Apache-2.0"
			(at 201.93 91.44 0)
			(effects
				(font
					(size 1.27 1.27)
					(thickness 0.15)
				)
				(justify left bottom)
				(hide yes)
			)
		)
		(property "Author" "Antmicro"
			(at 204.47 91.44 0)
			(effects
				(font
					(size 1.27 1.27)
					(thickness 0.15)
				)
				(justify left bottom)
				(hide yes)
			)
		)
		(property "Val" "10k"
			(at 177.8 110.49 90)
			(effects
				(font
					(size 1.27 1.27)
					(thickness 0.15)
				)
				(justify right)
			)
		)
		(property "Tolerance" "1%"
			(at 186.69 91.44 0)
			(effects
				(font
					(size 1.27 1.27)
				)
				(justify left bottom)
				(hide yes)
			)
		)
		(pin "2"
		)
		(pin "1"
		)
		(instances
			(project "OCuLink to 10GbE adapter"
				(path ""
					(reference "R98")
					(unit 1)
				)
			)
			(project "thunderbolt-to-10gbe-adapter"
				(path ""
					(reference "R154")
					(unit 1)
				)
			)
		)
	)
	(symbol
		(lib_id "antmicroResistors0402:R_10k_0402")
		(at 158.75 111.76 90)
		(unit 1)
		(exclude_from_sim no)
		(in_bom yes)
		(on_board yes)
		(dnp no)
		(property "Reference" "R146"
			(at 160.02 107.95 90)
			(effects
				(font
					(size 1.27 1.27)
					(thickness 0.15)
				)
				(justify right)
			)
		)
		(property "Value" "R_10k_0402"
			(at 171.45 91.44 0)
			(effects
				(font
					(size 1.27 1.27)
					(thickness 0.15)
				)
				(justify left bottom)
				(hide yes)
			)
		)
		(property "Footprint" "antmicro-footprints:R_0402_1005Metric"
			(at 173.99 91.44 0)
			(effects
				(font
					(size 1.27 1.27)
					(thickness 0.15)
				)
				(justify left bottom)
				(hide yes)
			)
		)
		(property "Datasheet" "https://www.bourns.com/docs/product-datasheets/cr.pdf"
			(at 176.53 91.44 0)
			(effects
				(font
					(size 1.27 1.27)
					(thickness 0.15)
				)
				(justify left bottom)
				(hide yes)
			)
		)
		(property "Description" "SMD Chip Resistor, 10 kohm, ± 1%, 62.5 mW, 0402 [1005 Metric], Thick Film, General Purpose"
			(at 158.75 111.76 0)
			(effects
				(font
					(size 1.27 1.27)
				)
				(hide yes)
			)
		)
		(property "MPN" "CR0402-FX-1002GLF"
			(at 179.07 91.44 0)
			(effects
				(font
					(size 1.27 1.27)
					(thickness 0.15)
				)
				(justify left bottom)
				(hide yes)
			)
		)
		(property "Manufacturer" "Bourns"
			(at 181.61 91.44 0)
			(effects
				(font
					(size 1.27 1.27)
					(thickness 0.15)
				)
				(justify left bottom)
				(hide yes)
			)
		)
		(property "License" "Apache-2.0"
			(at 184.15 91.44 0)
			(effects
				(font
					(size 1.27 1.27)
					(thickness 0.15)
				)
				(justify left bottom)
				(hide yes)
			)
		)
		(property "Author" "Antmicro"
			(at 186.69 91.44 0)
			(effects
				(font
					(size 1.27 1.27)
					(thickness 0.15)
				)
				(justify left bottom)
				(hide yes)
			)
		)
		(property "Val" "10k"
			(at 160.02 110.49 90)
			(effects
				(font
					(size 1.27 1.27)
					(thickness 0.15)
				)
				(justify right)
			)
		)
		(property "Tolerance" "1%"
			(at 168.91 91.44 0)
			(effects
				(font
					(size 1.27 1.27)
				)
				(justify left bottom)
				(hide yes)
			)
		)
		(pin "2"
		)
		(pin "1"
		)
		(instances
			(project "OCuLink to 10GbE adapter"
				(path ""
					(reference "R96")
					(unit 1)
				)
			)
			(project "thunderbolt-to-10gbe-adapter"
				(path ""
					(reference "R146")
					(unit 1)
				)
			)
		)
	)
	(symbol
		(lib_id "antmicropower:GND")
		(at 189.23 182.88 0)
		(unit 1)
		(exclude_from_sim no)
		(in_bom yes)
		(on_board yes)
		(dnp no)
		(property "Reference" "#PWR0403"
			(at 198.12 185.42 0)
			(effects
				(font
					(size 1.27 1.27)
					(thickness 0.15)
				)
				(justify left bottom)
				(hide yes)
			)
		)
		(property "Value" "GND"
			(at 189.23 186.69 0)
			(effects
				(font
					(size 1.27 1.27)
					(thickness 0.15)
				)
			)
		)
		(property "Footprint" ""
			(at 198.12 190.5 0)
			(effects
				(font
					(size 1.27 1.27)
					(thickness 0.15)
				)
				(justify left bottom)
				(hide yes)
			)
		)
		(property "Datasheet" ""
			(at 198.12 195.58 0)
			(effects
				(font
					(size 1.27 1.27)
					(thickness 0.15)
				)
				(justify left bottom)
				(hide yes)
			)
		)
		(property "Description" ""
			(at 189.23 182.88 0)
			(effects
				(font
					(size 1.27 1.27)
				)
				(hide yes)
			)
		)
		(property "Author" "Antmicro"
			(at 198.12 190.5 0)
			(effects
				(font
					(size 1.27 1.27)
					(thickness 0.15)
				)
				(justify left bottom)
				(hide yes)
			)
		)
		(property "License" "Apache-2.0"
			(at 198.12 193.04 0)
			(effects
				(font
					(size 1.27 1.27)
					(thickness 0.15)
				)
				(justify left bottom)
				(hide yes)
			)
		)
		(pin "1"
		)
		(instances
			(project "OCuLink to 10GbE adapter"
				(path ""
					(reference "#PWR0276")
					(unit 1)
				)
			)
			(project "thunderbolt-to-10gbe-adapter"
				(path ""
					(reference "#PWR0403")
					(unit 1)
				)
			)
		)
	)
	(symbol
		(lib_id "antmicroResistors0402:R_1k_0402")
		(at 213.36 193.04 90)
		(unit 1)
		(exclude_from_sim no)
		(in_bom yes)
		(on_board yes)
		(dnp no)
		(property "Reference" "R174"
			(at 214.884 189.23 90)
			(effects
				(font
					(size 1.27 1.27)
					(thickness 0.15)
				)
				(justify right)
			)
		)
		(property "Value" "R_1k_0402"
			(at 226.06 172.72 0)
			(effects
				(font
					(size 1.27 1.27)
					(thickness 0.15)
				)
				(justify left bottom)
				(hide yes)
			)
		)
		(property "Footprint" "antmicro-footprints:R_0402_1005Metric"
			(at 228.6 172.72 0)
			(effects
				(font
					(size 1.27 1.27)
					(thickness 0.15)
				)
				(justify left bottom)
				(hide yes)
			)
		)
		(property "Datasheet" "https://www.bourns.com/docs/product-datasheets/cr.pdf"
			(at 231.14 172.72 0)
			(effects
				(font
					(size 1.27 1.27)
					(thickness 0.15)
				)
				(justify left bottom)
				(hide yes)
			)
		)
		(property "Description" "SMD Chip Resistor, 1 kohm, ± 1%, 63 mW, 0402 [1005 Metric], Thick Film, General Purpose"
			(at 213.36 193.04 0)
			(effects
				(font
					(size 1.27 1.27)
				)
				(hide yes)
			)
		)
		(property "MPN" "CR0402-FX-1001GLF"
			(at 233.68 172.72 0)
			(effects
				(font
					(size 1.27 1.27)
					(thickness 0.15)
				)
				(justify left bottom)
				(hide yes)
			)
		)
		(property "Manufacturer" "Bourns"
			(at 236.22 172.72 0)
			(effects
				(font
					(size 1.27 1.27)
					(thickness 0.15)
				)
				(justify left bottom)
				(hide yes)
			)
		)
		(property "License" "Apache-2.0"
			(at 238.76 172.72 0)
			(effects
				(font
					(size 1.27 1.27)
					(thickness 0.15)
				)
				(justify left bottom)
				(hide yes)
			)
		)
		(property "Author" "Antmicro"
			(at 241.3 172.72 0)
			(effects
				(font
					(size 1.27 1.27)
					(thickness 0.15)
				)
				(justify left bottom)
				(hide yes)
			)
		)
		(property "Val" "1k"
			(at 214.884 191.77 90)
			(effects
				(font
					(size 1.27 1.27)
					(thickness 0.15)
				)
				(justify right)
			)
		)
		(property "Tolerance" "1%"
			(at 223.52 172.72 0)
			(effects
				(font
					(size 1.27 1.27)
				)
				(justify left bottom)
				(hide yes)
			)
		)
		(pin "2"
		)
		(pin "1"
		)
		(instances
			(project ""
				(path ""
					(reference "R116")
					(unit 1)
				)
			)
			(project "thunderbolt-to-10gbe-adapter"
				(path ""
					(reference "R174")
					(unit 1)
				)
			)
		)
	)
	(symbol
		(lib_id "antmicroTestPoints:TP_0.75mm_SMD")
		(at 133.35 78.74 180)
		(unit 1)
		(exclude_from_sim no)
		(in_bom no)
		(on_board yes)
		(dnp no)
		(property "Reference" "TP29"
			(at 129.032 78.74 0)
			(effects
				(font
					(size 1.27 1.27)
					(thickness 0.15)
				)
				(justify left)
			)
		)
		(property "Value" "TP_0.75mm_SMD"
			(at 123.19 74.93 0)
			(effects
				(font
					(size 1.27 1.27)
					(thickness 0.15)
				)
				(justify left bottom)
				(hide yes)
			)
		)
		(property "Footprint" "antmicro-footprints:TP_SMD_0.75mm"
			(at 123.19 72.39 0)
			(effects
				(font
					(size 1.27 1.27)
					(thickness 0.15)
				)
				(justify left bottom)
				(hide yes)
			)
		)
		(property "Datasheet" ""
			(at 115.57 66.04 0)
			(effects
				(font
					(size 1.27 1.27)
					(thickness 0.15)
				)
				(justify left bottom)
				(hide yes)
			)
		)
		(property "Description" "SMT test point"
			(at 133.35 78.74 0)
			(effects
				(font
					(size 1.27 1.27)
				)
				(hide yes)
			)
		)
		(property "MPN" ""
			(at 122.555 67.31 0)
			(effects
				(font
					(size 1.27 1.27)
					(thickness 0.15)
				)
				(justify left bottom)
				(hide yes)
			)
		)
		(property "Manufacturer" ""
			(at 122.555 72.39 0)
			(effects
				(font
					(size 1.27 1.27)
					(thickness 0.15)
				)
				(justify left bottom)
				(hide yes)
			)
		)
		(property "Author" "Antmicro"
			(at 123.19 69.85 0)
			(effects
				(font
					(size 1.27 1.27)
					(thickness 0.15)
				)
				(justify left bottom)
				(hide yes)
			)
		)
		(property "License" "Apache-2.0"
			(at 123.19 67.31 0)
			(effects
				(font
					(size 1.27 1.27)
					(thickness 0.15)
				)
				(justify left bottom)
				(hide yes)
			)
		)
		(pin "1"
		)
		(instances
			(project "OCuLink to 10GbE adapter"
				(path ""
					(reference "TP9")
					(unit 1)
				)
			)
			(project "thunderbolt-to-10gbe-adapter"
				(path ""
					(reference "TP29")
					(unit 1)
				)
			)
		)
	)
	(symbol
		(lib_id "antmicroLogicTranslatorsLevelShifters:NTS0102_TSSOP")
		(at 130.81 193.04 0)
		(mirror y)
		(unit 1)
		(exclude_from_sim no)
		(in_bom yes)
		(on_board yes)
		(dnp no)
		(fields_autoplaced yes)
		(property "Reference" "U16"
			(at 120.65 185.42 0)
			(effects
				(font
					(size 1.27 1.27)
					(thickness 0.15)
				)
			)
		)
		(property "Value" "NTS0102_TSSOP"
			(at 95.25 199.39 0)
			(effects
				(font
					(size 1.27 1.27)
					(thickness 0.15)
				)
				(justify left bottom)
				(hide yes)
			)
		)
		(property "Footprint" "antmicro-footprints:TSSOP-8_3x3mm_P0.65mm"
			(at 95.25 201.93 0)
			(effects
				(font
					(size 1.27 1.27)
					(thickness 0.15)
				)
				(justify left bottom)
				(hide yes)
			)
		)
		(property "Datasheet" "https://www.mouser.com/datasheet/2/302/NTS0102-1127324.pdf"
			(at 95.25 204.47 0)
			(effects
				(font
					(size 1.27 1.27)
					(thickness 0.15)
				)
				(justify left bottom)
				(hide yes)
			)
		)
		(property "Description" "Transceiver, 1.65 V to 3.6 V, TSSOP-8"
			(at 130.81 193.04 0)
			(effects
				(font
					(size 1.27 1.27)
				)
				(hide yes)
			)
		)
		(property "MPN" "NTS0102DP"
			(at 120.65 187.96 0)
			(effects
				(font
					(size 1.27 1.27)
					(thickness 0.15)
				)
			)
		)
		(property "Manufacturer" "NXP"
			(at 95.25 209.55 0)
			(effects
				(font
					(size 1.27 1.27)
					(thickness 0.15)
				)
				(justify left bottom)
				(hide yes)
			)
		)
		(property "Author" "Antmicro"
			(at 95.25 212.09 0)
			(effects
				(font
					(size 1.27 1.27)
					(thickness 0.15)
				)
				(justify left bottom)
				(hide yes)
			)
		)
		(property "License" "Apache-2.0"
			(at 95.25 214.63 0)
			(effects
				(font
					(size 1.27 1.27)
					(thickness 0.15)
				)
				(justify left bottom)
				(hide yes)
			)
		)
		(pin "5"
		)
		(pin "3"
		)
		(pin "1"
		)
		(pin "6"
		)
		(pin "7"
		)
		(pin "4"
		)
		(pin "2"
		)
		(pin "8"
		)
		(instances
			(project "OCuLink to 10GbE adapter"
				(path ""
					(reference "U8")
					(unit 1)
				)
			)
			(project "thunderbolt-to-10gbe-adapter"
				(path ""
					(reference "U16")
					(unit 1)
				)
			)
		)
	)
	(symbol
		(lib_id "antmicropower:GND")
		(at 177.8 182.88 0)
		(unit 1)
		(exclude_from_sim no)
		(in_bom yes)
		(on_board yes)
		(dnp no)
		(property "Reference" "#PWR0398"
			(at 186.69 185.42 0)
			(effects
				(font
					(size 1.27 1.27)
					(thickness 0.15)
				)
				(justify left bottom)
				(hide yes)
			)
		)
		(property "Value" "GND"
			(at 177.8 186.69 0)
			(effects
				(font
					(size 1.27 1.27)
					(thickness 0.15)
				)
			)
		)
		(property "Footprint" ""
			(at 186.69 190.5 0)
			(effects
				(font
					(size 1.27 1.27)
					(thickness 0.15)
				)
				(justify left bottom)
				(hide yes)
			)
		)
		(property "Datasheet" ""
			(at 186.69 195.58 0)
			(effects
				(font
					(size 1.27 1.27)
					(thickness 0.15)
				)
				(justify left bottom)
				(hide yes)
			)
		)
		(property "Description" ""
			(at 177.8 182.88 0)
			(effects
				(font
					(size 1.27 1.27)
				)
				(hide yes)
			)
		)
		(property "Author" "Antmicro"
			(at 186.69 190.5 0)
			(effects
				(font
					(size 1.27 1.27)
					(thickness 0.15)
				)
				(justify left bottom)
				(hide yes)
			)
		)
		(property "License" "Apache-2.0"
			(at 186.69 193.04 0)
			(effects
				(font
					(size 1.27 1.27)
					(thickness 0.15)
				)
				(justify left bottom)
				(hide yes)
			)
		)
		(pin "1"
		)
		(instances
			(project "OCuLink to 10GbE adapter"
				(path ""
					(reference "#PWR097")
					(unit 1)
				)
			)
			(project "thunderbolt-to-10gbe-adapter"
				(path ""
					(reference "#PWR0398")
					(unit 1)
				)
			)
		)
	)
	(symbol
		(lib_id "antmicropower:+3V3")
		(at 107.95 218.44 0)
		(mirror y)
		(unit 1)
		(exclude_from_sim no)
		(in_bom yes)
		(on_board yes)
		(dnp no)
		(property "Reference" "#PWR0380"
			(at 92.71 218.44 0)
			(effects
				(font
					(size 1.27 1.27)
					(thickness 0.15)
				)
				(justify left bottom)
				(hide yes)
			)
		)
		(property "Value" "+3V3"
			(at 107.95 214.63 0)
			(effects
				(font
					(size 1.27 1.27)
					(thickness 0.15)
				)
			)
		)
		(property "Footprint" ""
			(at 92.71 226.06 0)
			(effects
				(font
					(size 1.27 1.27)
					(thickness 0.15)
				)
				(justify left bottom)
				(hide yes)
			)
		)
		(property "Datasheet" ""
			(at 92.71 228.6 0)
			(effects
				(font
					(size 1.27 1.27)
					(thickness 0.15)
				)
				(justify left bottom)
				(hide yes)
			)
		)
		(property "Description" ""
			(at 107.95 218.44 0)
			(effects
				(font
					(size 1.27 1.27)
				)
				(hide yes)
			)
		)
		(property "Author" "Antmicro"
			(at 92.71 220.98 0)
			(effects
				(font
					(size 1.27 1.27)
					(thickness 0.15)
				)
				(justify left bottom)
				(hide yes)
			)
		)
		(property "License" "Apache-2.0"
			(at 92.71 223.52 0)
			(effects
				(font
					(size 1.27 1.27)
					(thickness 0.15)
				)
				(justify left bottom)
				(hide yes)
			)
		)
		(pin "1"
		)
		(instances
			(project "OCuLink to 10GbE adapter"
				(path ""
					(reference "#PWR0100")
					(unit 1)
				)
			)
			(project "thunderbolt-to-10gbe-adapter"
				(path ""
					(reference "#PWR0380")
					(unit 1)
				)
			)
		)
	)
	(symbol
		(lib_id "antmicroResistors0402:R_10k_0402")
		(at 195.58 111.76 90)
		(unit 1)
		(exclude_from_sim no)
		(in_bom yes)
		(on_board yes)
		(dnp no)
		(property "Reference" "R170"
			(at 196.85 107.95 90)
			(effects
				(font
					(size 1.27 1.27)
					(thickness 0.15)
				)
				(justify right)
			)
		)
		(property "Value" "R_10k_0402"
			(at 208.28 91.44 0)
			(effects
				(font
					(size 1.27 1.27)
					(thickness 0.15)
				)
				(justify left bottom)
				(hide yes)
			)
		)
		(property "Footprint" "antmicro-footprints:R_0402_1005Metric"
			(at 210.82 91.44 0)
			(effects
				(font
					(size 1.27 1.27)
					(thickness 0.15)
				)
				(justify left bottom)
				(hide yes)
			)
		)
		(property "Datasheet" "https://www.bourns.com/docs/product-datasheets/cr.pdf"
			(at 213.36 91.44 0)
			(effects
				(font
					(size 1.27 1.27)
					(thickness 0.15)
				)
				(justify left bottom)
				(hide yes)
			)
		)
		(property "Description" "SMD Chip Resistor, 10 kohm, ± 1%, 62.5 mW, 0402 [1005 Metric], Thick Film, General Purpose"
			(at 195.58 111.76 0)
			(effects
				(font
					(size 1.27 1.27)
				)
				(hide yes)
			)
		)
		(property "MPN" "CR0402-FX-1002GLF"
			(at 215.9 91.44 0)
			(effects
				(font
					(size 1.27 1.27)
					(thickness 0.15)
				)
				(justify left bottom)
				(hide yes)
			)
		)
		(property "Manufacturer" "Bourns"
			(at 218.44 91.44 0)
			(effects
				(font
					(size 1.27 1.27)
					(thickness 0.15)
				)
				(justify left bottom)
				(hide yes)
			)
		)
		(property "License" "Apache-2.0"
			(at 220.98 91.44 0)
			(effects
				(font
					(size 1.27 1.27)
					(thickness 0.15)
				)
				(justify left bottom)
				(hide yes)
			)
		)
		(property "Author" "Antmicro"
			(at 223.52 91.44 0)
			(effects
				(font
					(size 1.27 1.27)
					(thickness 0.15)
				)
				(justify left bottom)
				(hide yes)
			)
		)
		(property "Val" "10k"
			(at 196.85 110.49 90)
			(effects
				(font
					(size 1.27 1.27)
					(thickness 0.15)
				)
				(justify right)
			)
		)
		(property "Tolerance" "1%"
			(at 205.74 91.44 0)
			(effects
				(font
					(size 1.27 1.27)
				)
				(justify left bottom)
				(hide yes)
			)
		)
		(pin "2"
		)
		(pin "1"
		)
		(instances
			(project ""
				(path ""
					(reference "R100")
					(unit 1)
				)
			)
			(project "thunderbolt-to-10gbe-adapter"
				(path ""
					(reference "R170")
					(unit 1)
				)
			)
		)
	)
	(symbol
		(lib_id "antmicropower:+1V8")
		(at 308.61 204.47 0)
		(unit 1)
		(exclude_from_sim no)
		(in_bom yes)
		(on_board yes)
		(dnp no)
		(property "Reference" "#PWR0410"
			(at 323.85 207.01 0)
			(effects
				(font
					(size 1.27 1.27)
					(thickness 0.15)
				)
				(justify left bottom)
				(hide yes)
			)
		)
		(property "Value" "+1V88"
			(at 308.61 200.66 0)
			(effects
				(font
					(size 1.27 1.27)
					(thickness 0.15)
				)
			)
		)
		(property "Footprint" ""
			(at 323.85 212.09 0)
			(effects
				(font
					(size 1.27 1.27)
					(thickness 0.15)
				)
				(justify left bottom)
				(hide yes)
			)
		)
		(property "Datasheet" ""
			(at 323.85 214.63 0)
			(effects
				(font
					(size 1.27 1.27)
					(thickness 0.15)
				)
				(justify left bottom)
				(hide yes)
			)
		)
		(property "Description" ""
			(at 308.61 204.47 0)
			(effects
				(font
					(size 1.27 1.27)
				)
				(hide yes)
			)
		)
		(property "Author" "Antmicro"
			(at 323.85 209.55 0)
			(effects
				(font
					(size 1.27 1.27)
					(thickness 0.15)
				)
				(justify left bottom)
				(hide yes)
			)
		)
		(property "License" "Apache-2.0"
			(at 323.85 212.09 0)
			(effects
				(font
					(size 1.27 1.27)
					(thickness 0.15)
				)
				(justify left bottom)
				(hide yes)
			)
		)
		(pin "1"
		)
		(instances
			(project "OCuLink to 10GbE adapter"
				(path ""
					(reference "#PWR0278")
					(unit 1)
				)
			)
			(project "thunderbolt-to-10gbe-adapter"
				(path ""
					(reference "#PWR0410")
					(unit 1)
				)
			)
		)
	)
	(symbol
		(lib_id "antmicropower:GND")
		(at 162.56 88.9 0)
		(unit 1)
		(exclude_from_sim no)
		(in_bom yes)
		(on_board yes)
		(dnp no)
		(property "Reference" "#PWR0391"
			(at 171.45 91.44 0)
			(effects
				(font
					(size 1.27 1.27)
					(thickness 0.15)
				)
				(justify left bottom)
				(hide yes)
			)
		)
		(property "Value" "GND"
			(at 162.56 92.71 0)
			(effects
				(font
					(size 1.27 1.27)
					(thickness 0.15)
				)
			)
		)
		(property "Footprint" ""
			(at 171.45 96.52 0)
			(effects
				(font
					(size 1.27 1.27)
					(thickness 0.15)
				)
				(justify left bottom)
				(hide yes)
			)
		)
		(property "Datasheet" ""
			(at 171.45 101.6 0)
			(effects
				(font
					(size 1.27 1.27)
					(thickness 0.15)
				)
				(justify left bottom)
				(hide yes)
			)
		)
		(property "Description" ""
			(at 162.56 88.9 0)
			(effects
				(font
					(size 1.27 1.27)
				)
				(hide yes)
			)
		)
		(property "Author" "Antmicro"
			(at 171.45 96.52 0)
			(effects
				(font
					(size 1.27 1.27)
					(thickness 0.15)
				)
				(justify left bottom)
				(hide yes)
			)
		)
		(property "License" "Apache-2.0"
			(at 171.45 99.06 0)
			(effects
				(font
					(size 1.27 1.27)
					(thickness 0.15)
				)
				(justify left bottom)
				(hide yes)
			)
		)
		(pin "1"
		)
		(instances
			(project "OCuLink to 10GbE adapter"
				(path ""
					(reference "#PWR0259")
					(unit 1)
				)
			)
			(project "thunderbolt-to-10gbe-adapter"
				(path ""
					(reference "#PWR0391")
					(unit 1)
				)
			)
		)
	)
	(symbol
		(lib_id "antmicroResistors0402:R_100k_0402")
		(at 180.34 86.36 90)
		(unit 1)
		(exclude_from_sim no)
		(in_bom yes)
		(on_board yes)
		(dnp no)
		(property "Reference" "R157"
			(at 181.864 82.55 90)
			(effects
				(font
					(size 1.27 1.27)
					(thickness 0.15)
				)
				(justify right)
			)
		)
		(property "Value" "R_100k_0402"
			(at 193.04 66.04 0)
			(effects
				(font
					(size 1.27 1.27)
					(thickness 0.15)
				)
				(justify left bottom)
				(hide yes)
			)
		)
		(property "Footprint" "antmicro-footprints:R_0402_1005Metric"
			(at 195.58 66.04 0)
			(effects
				(font
					(size 1.27 1.27)
					(thickness 0.15)
				)
				(justify left bottom)
				(hide yes)
			)
		)
		(property "Datasheet" "https://www.bourns.com/docs/product-datasheets/cr.pdf"
			(at 198.12 66.04 0)
			(effects
				(font
					(size 1.27 1.27)
					(thickness 0.15)
				)
				(justify left bottom)
				(hide yes)
			)
		)
		(property "Description" "SMD Chip Resistor, 100 kohm, ± 1%, 62.5 mW, 0402 [1005 Metric], Thick Film, General Purpose"
			(at 180.34 86.36 0)
			(effects
				(font
					(size 1.27 1.27)
				)
				(hide yes)
			)
		)
		(property "MPN" "CR0402-FX-1003GLF"
			(at 200.66 66.04 0)
			(effects
				(font
					(size 1.27 1.27)
					(thickness 0.15)
				)
				(justify left bottom)
				(hide yes)
			)
		)
		(property "Manufacturer" "Bourns"
			(at 203.2 66.04 0)
			(effects
				(font
					(size 1.27 1.27)
					(thickness 0.15)
				)
				(justify left bottom)
				(hide yes)
			)
		)
		(property "License" "Apache-2.0"
			(at 205.74 66.04 0)
			(effects
				(font
					(size 1.27 1.27)
					(thickness 0.15)
				)
				(justify left bottom)
				(hide yes)
			)
		)
		(property "Author" "Antmicro"
			(at 208.28 66.04 0)
			(effects
				(font
					(size 1.27 1.27)
					(thickness 0.15)
				)
				(justify left bottom)
				(hide yes)
			)
		)
		(property "Val" "100k"
			(at 181.864 85.09 90)
			(effects
				(font
					(size 1.27 1.27)
					(thickness 0.15)
				)
				(justify right)
			)
		)
		(property "Tolerance" "1%"
			(at 190.5 66.04 0)
			(effects
				(font
					(size 1.27 1.27)
				)
				(justify left bottom)
				(hide yes)
			)
		)
		(pin "2"
		)
		(pin "1"
		)
		(instances
			(project "OCuLink to 10GbE adapter"
				(path ""
					(reference "R89")
					(unit 1)
				)
			)
			(project "thunderbolt-to-10gbe-adapter"
				(path ""
					(reference "R157")
					(unit 1)
				)
			)
		)
	)
	(symbol
		(lib_id "antmicropower:GND")
		(at 102.87 231.14 0)
		(mirror y)
		(unit 1)
		(exclude_from_sim no)
		(in_bom yes)
		(on_board yes)
		(dnp no)
		(property "Reference" "#PWR0376"
			(at 93.98 233.68 0)
			(effects
				(font
					(size 1.27 1.27)
					(thickness 0.15)
				)
				(justify left bottom)
				(hide yes)
			)
		)
		(property "Value" "GND"
			(at 102.87 234.95 0)
			(effects
				(font
					(size 1.27 1.27)
					(thickness 0.15)
				)
			)
		)
		(property "Footprint" ""
			(at 93.98 238.76 0)
			(effects
				(font
					(size 1.27 1.27)
					(thickness 0.15)
				)
				(justify left bottom)
				(hide yes)
			)
		)
		(property "Datasheet" ""
			(at 93.98 243.84 0)
			(effects
				(font
					(size 1.27 1.27)
					(thickness 0.15)
				)
				(justify left bottom)
				(hide yes)
			)
		)
		(property "Description" ""
			(at 102.87 231.14 0)
			(effects
				(font
					(size 1.27 1.27)
				)
				(hide yes)
			)
		)
		(property "Author" "Antmicro"
			(at 93.98 238.76 0)
			(effects
				(font
					(size 1.27 1.27)
					(thickness 0.15)
				)
				(justify left bottom)
				(hide yes)
			)
		)
		(property "License" "Apache-2.0"
			(at 93.98 241.3 0)
			(effects
				(font
					(size 1.27 1.27)
					(thickness 0.15)
				)
				(justify left bottom)
				(hide yes)
			)
		)
		(pin "1"
		)
		(instances
			(project "OCuLink to 10GbE adapter"
				(path ""
					(reference "#PWR0102")
					(unit 1)
				)
			)
			(project "thunderbolt-to-10gbe-adapter"
				(path ""
					(reference "#PWR0376")
					(unit 1)
				)
			)
		)
	)
	(symbol
		(lib_id "antmicroResistors0402:R_1k_0402")
		(at 190.5 251.46 90)
		(unit 1)
		(exclude_from_sim no)
		(in_bom yes)
		(on_board yes)
		(dnp no)
		(property "Reference" "R163"
			(at 192.024 247.65 90)
			(effects
				(font
					(size 1.27 1.27)
					(thickness 0.15)
				)
				(justify right)
			)
		)
		(property "Value" "R_1k_0402"
			(at 203.2 231.14 0)
			(effects
				(font
					(size 1.27 1.27)
					(thickness 0.15)
				)
				(justify left bottom)
				(hide yes)
			)
		)
		(property "Footprint" "antmicro-footprints:R_0402_1005Metric"
			(at 205.74 231.14 0)
			(effects
				(font
					(size 1.27 1.27)
					(thickness 0.15)
				)
				(justify left bottom)
				(hide yes)
			)
		)
		(property "Datasheet" "https://www.bourns.com/docs/product-datasheets/cr.pdf"
			(at 208.28 231.14 0)
			(effects
				(font
					(size 1.27 1.27)
					(thickness 0.15)
				)
				(justify left bottom)
				(hide yes)
			)
		)
		(property "Description" "SMD Chip Resistor, 1 kohm, ± 1%, 63 mW, 0402 [1005 Metric], Thick Film, General Purpose"
			(at 190.5 251.46 0)
			(effects
				(font
					(size 1.27 1.27)
				)
				(hide yes)
			)
		)
		(property "MPN" "CR0402-FX-1001GLF"
			(at 210.82 231.14 0)
			(effects
				(font
					(size 1.27 1.27)
					(thickness 0.15)
				)
				(justify left bottom)
				(hide yes)
			)
		)
		(property "Manufacturer" "Bourns"
			(at 213.36 231.14 0)
			(effects
				(font
					(size 1.27 1.27)
					(thickness 0.15)
				)
				(justify left bottom)
				(hide yes)
			)
		)
		(property "License" "Apache-2.0"
			(at 215.9 231.14 0)
			(effects
				(font
					(size 1.27 1.27)
					(thickness 0.15)
				)
				(justify left bottom)
				(hide yes)
			)
		)
		(property "Author" "Antmicro"
			(at 218.44 231.14 0)
			(effects
				(font
					(size 1.27 1.27)
					(thickness 0.15)
				)
				(justify left bottom)
				(hide yes)
			)
		)
		(property "Val" "1k"
			(at 192.024 250.19 90)
			(effects
				(font
					(size 1.27 1.27)
					(thickness 0.15)
				)
				(justify right)
			)
		)
		(property "Tolerance" "1%"
			(at 200.66 231.14 0)
			(effects
				(font
					(size 1.27 1.27)
				)
				(justify left bottom)
				(hide yes)
			)
		)
		(pin "1"
		)
		(pin "2"
		)
		(instances
			(project ""
				(path ""
					(reference "R121")
					(unit 1)
				)
			)
			(project "thunderbolt-to-10gbe-adapter"
				(path ""
					(reference "R163")
					(unit 1)
				)
			)
		)
	)
	(symbol
		(lib_id "antmicroResistors0402:R_2k_0402")
		(at 146.05 228.6 90)
		(unit 1)
		(exclude_from_sim no)
		(in_bom yes)
		(on_board yes)
		(dnp no)
		(fields_autoplaced yes)
		(property "Reference" "R143"
			(at 148.59 224.79 90)
			(effects
				(font
					(size 1.27 1.27)
					(thickness 0.15)
				)
				(justify right)
			)
		)
		(property "Value" "R_2k_0402"
			(at 158.75 208.28 0)
			(effects
				(font
					(size 1.27 1.27)
					(thickness 0.15)
				)
				(justify left bottom)
				(hide yes)
			)
		)
		(property "Footprint" "antmicro-footprints:R_0402_1005Metric"
			(at 161.29 208.28 0)
			(effects
				(font
					(size 1.27 1.27)
					(thickness 0.15)
				)
				(justify left bottom)
				(hide yes)
			)
		)
		(property "Datasheet" "https://www.bourns.com/docs/product-datasheets/cr.pdf"
			(at 163.83 208.28 0)
			(effects
				(font
					(size 1.27 1.27)
					(thickness 0.15)
				)
				(justify left bottom)
				(hide yes)
			)
		)
		(property "Description" "SMD Chip Resistor, 2 kohm, ± 1%, 62.5 mW, 0402 [1005 Metric], Thick Film, General Purpose"
			(at 176.53 208.28 0)
			(effects
				(font
					(size 1.27 1.27)
				)
				(justify left bottom)
				(hide yes)
			)
		)
		(property "MPN" "CR0402-FX-2001GLF"
			(at 166.37 208.28 0)
			(effects
				(font
					(size 1.27 1.27)
					(thickness 0.15)
				)
				(justify left bottom)
				(hide yes)
			)
		)
		(property "Manufacturer" "Bourns"
			(at 168.91 208.28 0)
			(effects
				(font
					(size 1.27 1.27)
					(thickness 0.15)
				)
				(justify left bottom)
				(hide yes)
			)
		)
		(property "License" "Apache-2.0"
			(at 171.45 208.28 0)
			(effects
				(font
					(size 1.27 1.27)
					(thickness 0.15)
				)
				(justify left bottom)
				(hide yes)
			)
		)
		(property "Author" "Antmicro"
			(at 173.99 208.28 0)
			(effects
				(font
					(size 1.27 1.27)
					(thickness 0.15)
				)
				(justify left bottom)
				(hide yes)
			)
		)
		(property "Val" "2k"
			(at 148.59 227.33 90)
			(effects
				(font
					(size 1.27 1.27)
					(thickness 0.15)
				)
				(justify right)
			)
		)
		(property "Tolerance" "1%"
			(at 156.21 208.28 0)
			(effects
				(font
					(size 1.27 1.27)
				)
				(justify left bottom)
				(hide yes)
			)
		)
		(pin "2"
		)
		(pin "1"
		)
		(instances
			(project "thunderbolt-to-10gbe-adapter"
				(path ""
					(reference "R143")
					(unit 1)
				)
			)
		)
	)
	(symbol
		(lib_id "antmicropower:GND")
		(at 107.95 203.2 0)
		(mirror y)
		(unit 1)
		(exclude_from_sim no)
		(in_bom yes)
		(on_board yes)
		(dnp no)
		(property "Reference" "#PWR0379"
			(at 99.06 205.74 0)
			(effects
				(font
					(size 1.27 1.27)
					(thickness 0.15)
				)
				(justify left bottom)
				(hide yes)
			)
		)
		(property "Value" "GND"
			(at 107.95 207.01 0)
			(effects
				(font
					(size 1.27 1.27)
					(thickness 0.15)
				)
			)
		)
		(property "Footprint" ""
			(at 99.06 210.82 0)
			(effects
				(font
					(size 1.27 1.27)
					(thickness 0.15)
				)
				(justify left bottom)
				(hide yes)
			)
		)
		(property "Datasheet" ""
			(at 99.06 215.9 0)
			(effects
				(font
					(size 1.27 1.27)
					(thickness 0.15)
				)
				(justify left bottom)
				(hide yes)
			)
		)
		(property "Description" ""
			(at 107.95 203.2 0)
			(effects
				(font
					(size 1.27 1.27)
				)
				(hide yes)
			)
		)
		(property "Author" "Antmicro"
			(at 99.06 210.82 0)
			(effects
				(font
					(size 1.27 1.27)
					(thickness 0.15)
				)
				(justify left bottom)
				(hide yes)
			)
		)
		(property "License" "Apache-2.0"
			(at 99.06 213.36 0)
			(effects
				(font
					(size 1.27 1.27)
					(thickness 0.15)
				)
				(justify left bottom)
				(hide yes)
			)
		)
		(pin "1"
		)
		(instances
			(project "OCuLink to 10GbE adapter"
				(path ""
					(reference "#PWR0111")
					(unit 1)
				)
			)
			(project "thunderbolt-to-10gbe-adapter"
				(path ""
					(reference "#PWR0379")
					(unit 1)
				)
			)
		)
	)
	(symbol
		(lib_id "antmicroResistors0402:R_10k_0402")
		(at 314.96 104.14 90)
		(unit 1)
		(exclude_from_sim no)
		(in_bom yes)
		(on_board yes)
		(dnp no)
		(property "Reference" "R182"
			(at 316.484 100.33 90)
			(effects
				(font
					(size 1.27 1.27)
					(thickness 0.15)
				)
				(justify right)
			)
		)
		(property "Value" "R_10k_0402"
			(at 327.66 83.82 0)
			(effects
				(font
					(size 1.27 1.27)
					(thickness 0.15)
				)
				(justify left bottom)
				(hide yes)
			)
		)
		(property "Footprint" "antmicro-footprints:R_0402_1005Metric"
			(at 330.2 83.82 0)
			(effects
				(font
					(size 1.27 1.27)
					(thickness 0.15)
				)
				(justify left bottom)
				(hide yes)
			)
		)
		(property "Datasheet" "https://www.bourns.com/docs/product-datasheets/cr.pdf"
			(at 332.74 83.82 0)
			(effects
				(font
					(size 1.27 1.27)
					(thickness 0.15)
				)
				(justify left bottom)
				(hide yes)
			)
		)
		(property "Description" "SMD Chip Resistor, 10 kohm, ± 1%, 62.5 mW, 0402 [1005 Metric], Thick Film, General Purpose"
			(at 314.96 104.14 0)
			(effects
				(font
					(size 1.27 1.27)
				)
				(hide yes)
			)
		)
		(property "MPN" "CR0402-FX-1002GLF"
			(at 335.28 83.82 0)
			(effects
				(font
					(size 1.27 1.27)
					(thickness 0.15)
				)
				(justify left bottom)
				(hide yes)
			)
		)
		(property "Manufacturer" "Bourns"
			(at 337.82 83.82 0)
			(effects
				(font
					(size 1.27 1.27)
					(thickness 0.15)
				)
				(justify left bottom)
				(hide yes)
			)
		)
		(property "License" "Apache-2.0"
			(at 340.36 83.82 0)
			(effects
				(font
					(size 1.27 1.27)
					(thickness 0.15)
				)
				(justify left bottom)
				(hide yes)
			)
		)
		(property "Author" "Antmicro"
			(at 342.9 83.82 0)
			(effects
				(font
					(size 1.27 1.27)
					(thickness 0.15)
				)
				(justify left bottom)
				(hide yes)
			)
		)
		(property "Val" "10k"
			(at 316.484 102.87 90)
			(effects
				(font
					(size 1.27 1.27)
					(thickness 0.15)
				)
				(justify right)
			)
		)
		(property "Tolerance" "1%"
			(at 325.12 83.82 0)
			(effects
				(font
					(size 1.27 1.27)
				)
				(justify left bottom)
				(hide yes)
			)
		)
		(pin "2"
		)
		(pin "1"
		)
		(instances
			(project "OCuLink to 10GbE adapter"
				(path ""
					(reference "R94")
					(unit 1)
				)
			)
			(project "thunderbolt-to-10gbe-adapter"
				(path ""
					(reference "R182")
					(unit 1)
				)
			)
		)
	)
	(symbol
		(lib_id "antmicropower:GND")
		(at 147.32 245.11 0)
		(mirror y)
		(unit 1)
		(exclude_from_sim no)
		(in_bom yes)
		(on_board yes)
		(dnp no)
		(property "Reference" "#PWR0386"
			(at 138.43 247.65 0)
			(effects
				(font
					(size 1.27 1.27)
					(thickness 0.15)
				)
				(justify left bottom)
				(hide yes)
			)
		)
		(property "Value" "GND"
			(at 147.32 248.92 0)
			(effects
				(font
					(size 1.27 1.27)
					(thickness 0.15)
				)
			)
		)
		(property "Footprint" ""
			(at 138.43 252.73 0)
			(effects
				(font
					(size 1.27 1.27)
					(thickness 0.15)
				)
				(justify left bottom)
				(hide yes)
			)
		)
		(property "Datasheet" ""
			(at 138.43 257.81 0)
			(effects
				(font
					(size 1.27 1.27)
					(thickness 0.15)
				)
				(justify left bottom)
				(hide yes)
			)
		)
		(property "Description" ""
			(at 147.32 245.11 0)
			(effects
				(font
					(size 1.27 1.27)
				)
				(hide yes)
			)
		)
		(property "Author" "Antmicro"
			(at 138.43 252.73 0)
			(effects
				(font
					(size 1.27 1.27)
					(thickness 0.15)
				)
				(justify left bottom)
				(hide yes)
			)
		)
		(property "License" "Apache-2.0"
			(at 138.43 255.27 0)
			(effects
				(font
					(size 1.27 1.27)
					(thickness 0.15)
				)
				(justify left bottom)
				(hide yes)
			)
		)
		(pin "1"
		)
		(instances
			(project "OCuLink to 10GbE adapter"
				(path ""
					(reference "#PWR0103")
					(unit 1)
				)
			)
			(project "thunderbolt-to-10gbe-adapter"
				(path ""
					(reference "#PWR0386")
					(unit 1)
				)
			)
		)
	)
	(symbol
		(lib_id "antmicropower:GND")
		(at 195.58 139.7 0)
		(unit 1)
		(exclude_from_sim no)
		(in_bom yes)
		(on_board yes)
		(dnp no)
		(property "Reference" "#PWR0405"
			(at 204.47 142.24 0)
			(effects
				(font
					(size 1.27 1.27)
					(thickness 0.15)
				)
				(justify left bottom)
				(hide yes)
			)
		)
		(property "Value" "GND"
			(at 195.58 143.51 0)
			(effects
				(font
					(size 1.27 1.27)
					(thickness 0.15)
				)
			)
		)
		(property "Footprint" ""
			(at 204.47 147.32 0)
			(effects
				(font
					(size 1.27 1.27)
					(thickness 0.15)
				)
				(justify left bottom)
				(hide yes)
			)
		)
		(property "Datasheet" ""
			(at 204.47 152.4 0)
			(effects
				(font
					(size 1.27 1.27)
					(thickness 0.15)
				)
				(justify left bottom)
				(hide yes)
			)
		)
		(property "Description" ""
			(at 195.58 139.7 0)
			(effects
				(font
					(size 1.27 1.27)
				)
				(hide yes)
			)
		)
		(property "Author" "Antmicro"
			(at 204.47 147.32 0)
			(effects
				(font
					(size 1.27 1.27)
					(thickness 0.15)
				)
				(justify left bottom)
				(hide yes)
			)
		)
		(property "License" "Apache-2.0"
			(at 204.47 149.86 0)
			(effects
				(font
					(size 1.27 1.27)
					(thickness 0.15)
				)
				(justify left bottom)
				(hide yes)
			)
		)
		(pin "1"
		)
		(instances
			(project "OCuLink to 10GbE adapter"
				(path ""
					(reference "#PWR0273")
					(unit 1)
				)
			)
			(project "thunderbolt-to-10gbe-adapter"
				(path ""
					(reference "#PWR0405")
					(unit 1)
				)
			)
		)
	)
	(symbol
		(lib_id "antmicroTestPoints:TP_0.75mm_SMD")
		(at 133.35 66.04 180)
		(unit 1)
		(exclude_from_sim no)
		(in_bom no)
		(on_board yes)
		(dnp no)
		(property "Reference" "TP24"
			(at 129.032 66.04 0)
			(effects
				(font
					(size 1.27 1.27)
					(thickness 0.15)
				)
				(justify left)
			)
		)
		(property "Value" "TP_0.75mm_SMD"
			(at 123.19 62.23 0)
			(effects
				(font
					(size 1.27 1.27)
					(thickness 0.15)
				)
				(justify left bottom)
				(hide yes)
			)
		)
		(property "Footprint" "antmicro-footprints:TP_SMD_0.75mm"
			(at 123.19 59.69 0)
			(effects
				(font
					(size 1.27 1.27)
					(thickness 0.15)
				)
				(justify left bottom)
				(hide yes)
			)
		)
		(property "Datasheet" ""
			(at 115.57 53.34 0)
			(effects
				(font
					(size 1.27 1.27)
					(thickness 0.15)
				)
				(justify left bottom)
				(hide yes)
			)
		)
		(property "Description" "SMT test point"
			(at 133.35 66.04 0)
			(effects
				(font
					(size 1.27 1.27)
				)
				(hide yes)
			)
		)
		(property "MPN" ""
			(at 122.555 54.61 0)
			(effects
				(font
					(size 1.27 1.27)
					(thickness 0.15)
				)
				(justify left bottom)
				(hide yes)
			)
		)
		(property "Manufacturer" ""
			(at 122.555 59.69 0)
			(effects
				(font
					(size 1.27 1.27)
					(thickness 0.15)
				)
				(justify left bottom)
				(hide yes)
			)
		)
		(property "Author" "Antmicro"
			(at 123.19 57.15 0)
			(effects
				(font
					(size 1.27 1.27)
					(thickness 0.15)
				)
				(justify left bottom)
				(hide yes)
			)
		)
		(property "License" "Apache-2.0"
			(at 123.19 54.61 0)
			(effects
				(font
					(size 1.27 1.27)
					(thickness 0.15)
				)
				(justify left bottom)
				(hide yes)
			)
		)
		(pin "1"
		)
		(instances
			(project "OCuLink to 10GbE adapter"
				(path ""
					(reference "TP4")
					(unit 1)
				)
			)
			(project "thunderbolt-to-10gbe-adapter"
				(path ""
					(reference "TP24")
					(unit 1)
				)
			)
		)
	)
	(symbol
		(lib_id "antmicroResistors0402:R_0R_0402")
		(at 146.05 127 0)
		(unit 1)
		(exclude_from_sim no)
		(in_bom yes)
		(on_board yes)
		(dnp no)
		(property "Reference" "R142"
			(at 146.05 125.73 0)
			(effects
				(font
					(size 1.27 1.27)
					(thickness 0.15)
				)
				(justify right)
			)
		)
		(property "Value" "R_0R_0402"
			(at 166.37 139.7 0)
			(effects
				(font
					(size 1.27 1.27)
					(thickness 0.15)
				)
				(justify left bottom)
				(hide yes)
			)
		)
		(property "Footprint" "antmicro-footprints:R_0402_1005Metric"
			(at 166.37 142.24 0)
			(effects
				(font
					(size 1.27 1.27)
					(thickness 0.15)
				)
				(justify left bottom)
				(hide yes)
			)
		)
		(property "Datasheet" "https://industrial.panasonic.com/cdbs/www-data/pdf/RDA0000/AOA0000C301.pdf"
			(at 166.37 144.78 0)
			(effects
				(font
					(size 1.27 1.27)
					(thickness 0.15)
				)
				(justify left bottom)
				(hide yes)
			)
		)
		(property "Description" "SMD Chip Resistor, Jumper, 0 ohm, 100 mW, 0402 [1005 Metric], Thick Film, General Purpose"
			(at 146.05 127 0)
			(effects
				(font
					(size 1.27 1.27)
				)
				(hide yes)
			)
		)
		(property "MPN" "ERJ2GE0R00X"
			(at 166.37 147.32 0)
			(effects
				(font
					(size 1.27 1.27)
					(thickness 0.15)
				)
				(justify left bottom)
				(hide yes)
			)
		)
		(property "Manufacturer" "Panasonic"
			(at 166.37 149.86 0)
			(effects
				(font
					(size 1.27 1.27)
					(thickness 0.15)
				)
				(justify left bottom)
				(hide yes)
			)
		)
		(property "License" "Apache-2.0"
			(at 166.37 152.4 0)
			(effects
				(font
					(size 1.27 1.27)
					(thickness 0.15)
				)
				(justify left bottom)
				(hide yes)
			)
		)
		(property "Author" "Antmicro"
			(at 166.37 154.94 0)
			(effects
				(font
					(size 1.27 1.27)
					(thickness 0.15)
				)
				(justify left bottom)
				(hide yes)
			)
		)
		(property "Val" "0R"
			(at 151.13 125.73 0)
			(effects
				(font
					(size 1.27 1.27)
					(thickness 0.15)
				)
				(justify left)
			)
		)
		(property "Tolerance" "~"
			(at 166.37 137.16 0)
			(effects
				(font
					(size 1.27 1.27)
				)
				(justify left bottom)
				(hide yes)
			)
		)
		(property "Current" "1A"
			(at 166.37 157.48 0)
			(effects
				(font
					(size 1.27 1.27)
					(thickness 0.15)
				)
				(justify left bottom)
				(hide yes)
			)
		)
		(pin "1"
		)
		(pin "2"
		)
		(instances
			(project "OCuLink to 10GbE adapter"
				(path ""
					(reference "R104")
					(unit 1)
				)
			)
			(project "thunderbolt-to-10gbe-adapter"
				(path ""
					(reference "R142")
					(unit 1)
				)
			)
		)
	)
	(symbol
		(lib_id "antmicropower:+3V3")
		(at 151.13 45.72 0)
		(unit 1)
		(exclude_from_sim no)
		(in_bom yes)
		(on_board yes)
		(dnp no)
		(property "Reference" "#PWR0387"
			(at 166.37 45.72 0)
			(effects
				(font
					(size 1.27 1.27)
					(thickness 0.15)
				)
				(justify left bottom)
				(hide yes)
			)
		)
		(property "Value" "+3V3"
			(at 151.13 41.91 0)
			(effects
				(font
					(size 1.27 1.27)
					(thickness 0.15)
				)
			)
		)
		(property "Footprint" ""
			(at 166.37 53.34 0)
			(effects
				(font
					(size 1.27 1.27)
					(thickness 0.15)
				)
				(justify left bottom)
				(hide yes)
			)
		)
		(property "Datasheet" ""
			(at 166.37 55.88 0)
			(effects
				(font
					(size 1.27 1.27)
					(thickness 0.15)
				)
				(justify left bottom)
				(hide yes)
			)
		)
		(property "Description" ""
			(at 151.13 45.72 0)
			(effects
				(font
					(size 1.27 1.27)
				)
				(hide yes)
			)
		)
		(property "Author" "Antmicro"
			(at 166.37 48.26 0)
			(effects
				(font
					(size 1.27 1.27)
					(thickness 0.15)
				)
				(justify left bottom)
				(hide yes)
			)
		)
		(property "License" "Apache-2.0"
			(at 166.37 50.8 0)
			(effects
				(font
					(size 1.27 1.27)
					(thickness 0.15)
				)
				(justify left bottom)
				(hide yes)
			)
		)
		(pin "1"
		)
		(instances
			(project "OCuLink to 10GbE adapter"
				(path ""
					(reference "#PWR0258")
					(unit 1)
				)
			)
			(project "thunderbolt-to-10gbe-adapter"
				(path ""
					(reference "#PWR0387")
					(unit 1)
				)
			)
		)
	)
	(symbol
		(lib_id "antmicropower:GND")
		(at 96.52 245.11 0)
		(mirror y)
		(unit 1)
		(exclude_from_sim no)
		(in_bom yes)
		(on_board yes)
		(dnp no)
		(property "Reference" "#PWR0374"
			(at 87.63 247.65 0)
			(effects
				(font
					(size 1.27 1.27)
					(thickness 0.15)
				)
				(justify left bottom)
				(hide yes)
			)
		)
		(property "Value" "GND"
			(at 96.52 248.92 0)
			(effects
				(font
					(size 1.27 1.27)
					(thickness 0.15)
				)
			)
		)
		(property "Footprint" ""
			(at 87.63 252.73 0)
			(effects
				(font
					(size 1.27 1.27)
					(thickness 0.15)
				)
				(justify left bottom)
				(hide yes)
			)
		)
		(property "Datasheet" ""
			(at 87.63 257.81 0)
			(effects
				(font
					(size 1.27 1.27)
					(thickness 0.15)
				)
				(justify left bottom)
				(hide yes)
			)
		)
		(property "Description" ""
			(at 96.52 245.11 0)
			(effects
				(font
					(size 1.27 1.27)
				)
				(hide yes)
			)
		)
		(property "Author" "Antmicro"
			(at 87.63 252.73 0)
			(effects
				(font
					(size 1.27 1.27)
					(thickness 0.15)
				)
				(justify left bottom)
				(hide yes)
			)
		)
		(property "License" "Apache-2.0"
			(at 87.63 255.27 0)
			(effects
				(font
					(size 1.27 1.27)
					(thickness 0.15)
				)
				(justify left bottom)
				(hide yes)
			)
		)
		(pin "1"
		)
		(instances
			(project "OCuLink to 10GbE adapter"
				(path ""
					(reference "#PWR0105")
					(unit 1)
				)
			)
			(project "thunderbolt-to-10gbe-adapter"
				(path ""
					(reference "#PWR0374")
					(unit 1)
				)
			)
		)
	)
	(symbol
		(lib_id "antmicropower:GND")
		(at 189.23 88.9 0)
		(unit 1)
		(exclude_from_sim no)
		(in_bom yes)
		(on_board yes)
		(dnp no)
		(property "Reference" "#PWR0402"
			(at 198.12 91.44 0)
			(effects
				(font
					(size 1.27 1.27)
					(thickness 0.15)
				)
				(justify left bottom)
				(hide yes)
			)
		)
		(property "Value" "GND"
			(at 189.23 92.71 0)
			(effects
				(font
					(size 1.27 1.27)
					(thickness 0.15)
				)
			)
		)
		(property "Footprint" ""
			(at 198.12 96.52 0)
			(effects
				(font
					(size 1.27 1.27)
					(thickness 0.15)
				)
				(justify left bottom)
				(hide yes)
			)
		)
		(property "Datasheet" ""
			(at 198.12 101.6 0)
			(effects
				(font
					(size 1.27 1.27)
					(thickness 0.15)
				)
				(justify left bottom)
				(hide yes)
			)
		)
		(property "Description" ""
			(at 189.23 88.9 0)
			(effects
				(font
					(size 1.27 1.27)
				)
				(hide yes)
			)
		)
		(property "Author" "Antmicro"
			(at 198.12 96.52 0)
			(effects
				(font
					(size 1.27 1.27)
					(thickness 0.15)
				)
				(justify left bottom)
				(hide yes)
			)
		)
		(property "License" "Apache-2.0"
			(at 198.12 99.06 0)
			(effects
				(font
					(size 1.27 1.27)
					(thickness 0.15)
				)
				(justify left bottom)
				(hide yes)
			)
		)
		(pin "1"
		)
		(instances
			(project "OCuLink to 10GbE adapter"
				(path ""
					(reference "#PWR0262")
					(unit 1)
				)
			)
			(project "thunderbolt-to-10gbe-adapter"
				(path ""
					(reference "#PWR0402")
					(unit 1)
				)
			)
		)
	)
	(symbol
		(lib_id "antmicroResistors0402:R_0R_0402")
		(at 71.12 129.54 0)
		(unit 1)
		(exclude_from_sim no)
		(in_bom yes)
		(on_board yes)
		(dnp no)
		(property "Reference" "R137"
			(at 71.12 128.27 0)
			(effects
				(font
					(size 1.27 1.27)
					(thickness 0.15)
				)
				(justify right)
			)
		)
		(property "Value" "R_0R_0402"
			(at 91.44 142.24 0)
			(effects
				(font
					(size 1.27 1.27)
					(thickness 0.15)
				)
				(justify left bottom)
				(hide yes)
			)
		)
		(property "Footprint" "antmicro-footprints:R_0402_1005Metric"
			(at 91.44 144.78 0)
			(effects
				(font
					(size 1.27 1.27)
					(thickness 0.15)
				)
				(justify left bottom)
				(hide yes)
			)
		)
		(property "Datasheet" "https://industrial.panasonic.com/cdbs/www-data/pdf/RDA0000/AOA0000C301.pdf"
			(at 91.44 147.32 0)
			(effects
				(font
					(size 1.27 1.27)
					(thickness 0.15)
				)
				(justify left bottom)
				(hide yes)
			)
		)
		(property "Description" "SMD Chip Resistor, Jumper, 0 ohm, 100 mW, 0402 [1005 Metric], Thick Film, General Purpose"
			(at 71.12 129.54 0)
			(effects
				(font
					(size 1.27 1.27)
				)
				(hide yes)
			)
		)
		(property "MPN" "ERJ2GE0R00X"
			(at 91.44 149.86 0)
			(effects
				(font
					(size 1.27 1.27)
					(thickness 0.15)
				)
				(justify left bottom)
				(hide yes)
			)
		)
		(property "Manufacturer" "Panasonic"
			(at 91.44 152.4 0)
			(effects
				(font
					(size 1.27 1.27)
					(thickness 0.15)
				)
				(justify left bottom)
				(hide yes)
			)
		)
		(property "License" "Apache-2.0"
			(at 91.44 154.94 0)
			(effects
				(font
					(size 1.27 1.27)
					(thickness 0.15)
				)
				(justify left bottom)
				(hide yes)
			)
		)
		(property "Author" "Antmicro"
			(at 91.44 157.48 0)
			(effects
				(font
					(size 1.27 1.27)
					(thickness 0.15)
				)
				(justify left bottom)
				(hide yes)
			)
		)
		(property "Val" "0R"
			(at 76.2 128.27 0)
			(effects
				(font
					(size 1.27 1.27)
					(thickness 0.15)
				)
				(justify left)
			)
		)
		(property "Tolerance" "~"
			(at 91.44 139.7 0)
			(effects
				(font
					(size 1.27 1.27)
				)
				(justify left bottom)
				(hide yes)
			)
		)
		(property "Current" "1A"
			(at 91.44 160.02 0)
			(effects
				(font
					(size 1.27 1.27)
					(thickness 0.15)
				)
				(justify left bottom)
				(hide yes)
			)
		)
		(pin "1"
		)
		(pin "2"
		)
		(instances
			(project "OCuLink to 10GbE adapter"
				(path ""
					(reference "R105")
					(unit 1)
				)
			)
			(project "thunderbolt-to-10gbe-adapter"
				(path ""
					(reference "R137")
					(unit 1)
				)
			)
		)
	)
	(symbol
		(lib_id "antmicropower:+3V3")
		(at 314.96 93.98 0)
		(unit 1)
		(exclude_from_sim no)
		(in_bom yes)
		(on_board yes)
		(dnp no)
		(property "Reference" "#PWR0411"
			(at 330.2 93.98 0)
			(effects
				(font
					(size 1.27 1.27)
					(thickness 0.15)
				)
				(justify left bottom)
				(hide yes)
			)
		)
		(property "Value" "+3V3"
			(at 314.96 90.17 0)
			(effects
				(font
					(size 1.27 1.27)
					(thickness 0.15)
				)
			)
		)
		(property "Footprint" ""
			(at 330.2 101.6 0)
			(effects
				(font
					(size 1.27 1.27)
					(thickness 0.15)
				)
				(justify left bottom)
				(hide yes)
			)
		)
		(property "Datasheet" ""
			(at 330.2 104.14 0)
			(effects
				(font
					(size 1.27 1.27)
					(thickness 0.15)
				)
				(justify left bottom)
				(hide yes)
			)
		)
		(property "Description" ""
			(at 314.96 93.98 0)
			(effects
				(font
					(size 1.27 1.27)
				)
				(hide yes)
			)
		)
		(property "Author" "Antmicro"
			(at 330.2 96.52 0)
			(effects
				(font
					(size 1.27 1.27)
					(thickness 0.15)
				)
				(justify left bottom)
				(hide yes)
			)
		)
		(property "License" "Apache-2.0"
			(at 330.2 99.06 0)
			(effects
				(font
					(size 1.27 1.27)
					(thickness 0.15)
				)
				(justify left bottom)
				(hide yes)
			)
		)
		(pin "1"
		)
		(instances
			(project "OCuLink to 10GbE adapter"
				(path ""
					(reference "#PWR0263")
					(unit 1)
				)
			)
			(project "thunderbolt-to-10gbe-adapter"
				(path ""
					(reference "#PWR0411")
					(unit 1)
				)
			)
		)
	)
	(symbol
		(lib_id "antmicroCapacitors0402:C_5p6_0402")
		(at 177.8 180.34 90)
		(unit 1)
		(exclude_from_sim no)
		(in_bom yes)
		(on_board yes)
		(dnp no)
		(property "Reference" "C281"
			(at 179.832 176.53 90)
			(effects
				(font
					(size 1.27 1.27)
					(thickness 0.15)
				)
				(justify right)
			)
		)
		(property "Value" "C_5p6_0402"
			(at 187.96 160.02 0)
			(effects
				(font
					(size 1.27 1.27)
					(thickness 0.15)
				)
				(justify left bottom)
				(hide yes)
			)
		)
		(property "Footprint" "antmicro-footprints:C_0402_1005Metric"
			(at 190.5 160.02 0)
			(effects
				(font
					(size 1.27 1.27)
					(thickness 0.15)
				)
				(justify left bottom)
				(hide yes)
			)
		)
		(property "Datasheet" "https://www.mouser.com/datasheet/3/76/2/GCM1555C1H5R6BA16_01A.pdf"
			(at 193.04 160.02 0)
			(effects
				(font
					(size 1.27 1.27)
					(thickness 0.15)
				)
				(justify left bottom)
				(hide yes)
			)
		)
		(property "Description" "Multilayer Ceramic Capacitors MLCC - SMD/SMT 5.6 pF 50 VDC 0.1 pF 0402 C0G (NP0) AEC-Q200"
			(at 177.8 180.34 0)
			(effects
				(font
					(size 1.27 1.27)
				)
				(hide yes)
			)
		)
		(property "MPN" "GCM1555C1H5R6BA16D"
			(at 195.58 160.02 0)
			(effects
				(font
					(size 1.27 1.27)
					(thickness 0.15)
				)
				(justify left bottom)
				(hide yes)
			)
		)
		(property "Manufacturer" "Murata"
			(at 198.12 160.02 0)
			(effects
				(font
					(size 1.27 1.27)
					(thickness 0.15)
				)
				(justify left bottom)
				(hide yes)
			)
		)
		(property "License" "Apache-2.0"
			(at 200.66 160.02 0)
			(effects
				(font
					(size 1.27 1.27)
					(thickness 0.15)
				)
				(justify left bottom)
				(hide yes)
			)
		)
		(property "Author" "Antmicro"
			(at 203.2 160.02 0)
			(effects
				(font
					(size 1.27 1.27)
					(thickness 0.15)
				)
				(justify left bottom)
				(hide yes)
			)
		)
		(property "Val" "5p6"
			(at 179.832 179.07 90)
			(effects
				(font
					(size 1.27 1.27)
					(thickness 0.15)
				)
				(justify right)
			)
		)
		(property "Voltage" "50V"
			(at 205.74 160.02 0)
			(effects
				(font
					(size 1.27 1.27)
				)
				(justify left bottom)
				(hide yes)
			)
		)
		(property "Dielectric" "C0G"
			(at 208.28 160.02 0)
			(effects
				(font
					(size 1.27 1.27)
				)
				(justify left bottom)
				(hide yes)
			)
		)
		(pin "2"
		)
		(pin "1"
		)
		(instances
			(project "OCuLink to 10GbE adapter"
				(path ""
					(reference "C73")
					(unit 1)
				)
			)
			(project "thunderbolt-to-10gbe-adapter"
				(path ""
					(reference "C281")
					(unit 1)
				)
			)
		)
	)
	(symbol
		(lib_id "antmicroResistors0402:R_10k_0402")
		(at 151.13 111.76 90)
		(unit 1)
		(exclude_from_sim no)
		(in_bom yes)
		(on_board yes)
		(dnp no)
		(property "Reference" "R145"
			(at 152.4 107.95 90)
			(effects
				(font
					(size 1.27 1.27)
					(thickness 0.15)
				)
				(justify right)
			)
		)
		(property "Value" "R_10k_0402"
			(at 163.83 91.44 0)
			(effects
				(font
					(size 1.27 1.27)
					(thickness 0.15)
				)
				(justify left bottom)
				(hide yes)
			)
		)
		(property "Footprint" "antmicro-footprints:R_0402_1005Metric"
			(at 166.37 91.44 0)
			(effects
				(font
					(size 1.27 1.27)
					(thickness 0.15)
				)
				(justify left bottom)
				(hide yes)
			)
		)
		(property "Datasheet" "https://www.bourns.com/docs/product-datasheets/cr.pdf"
			(at 168.91 91.44 0)
			(effects
				(font
					(size 1.27 1.27)
					(thickness 0.15)
				)
				(justify left bottom)
				(hide yes)
			)
		)
		(property "Description" "SMD Chip Resistor, 10 kohm, ± 1%, 62.5 mW, 0402 [1005 Metric], Thick Film, General Purpose"
			(at 151.13 111.76 0)
			(effects
				(font
					(size 1.27 1.27)
				)
				(hide yes)
			)
		)
		(property "MPN" "CR0402-FX-1002GLF"
			(at 171.45 91.44 0)
			(effects
				(font
					(size 1.27 1.27)
					(thickness 0.15)
				)
				(justify left bottom)
				(hide yes)
			)
		)
		(property "Manufacturer" "Bourns"
			(at 173.99 91.44 0)
			(effects
				(font
					(size 1.27 1.27)
					(thickness 0.15)
				)
				(justify left bottom)
				(hide yes)
			)
		)
		(property "License" "Apache-2.0"
			(at 176.53 91.44 0)
			(effects
				(font
					(size 1.27 1.27)
					(thickness 0.15)
				)
				(justify left bottom)
				(hide yes)
			)
		)
		(property "Author" "Antmicro"
			(at 179.07 91.44 0)
			(effects
				(font
					(size 1.27 1.27)
					(thickness 0.15)
				)
				(justify left bottom)
				(hide yes)
			)
		)
		(property "Val" "10k"
			(at 152.4 110.49 90)
			(effects
				(font
					(size 1.27 1.27)
					(thickness 0.15)
				)
				(justify right)
			)
		)
		(property "Tolerance" "1%"
			(at 161.29 91.44 0)
			(effects
				(font
					(size 1.27 1.27)
				)
				(justify left bottom)
				(hide yes)
			)
		)
		(pin "2"
		)
		(pin "1"
		)
		(instances
			(project "OCuLink to 10GbE adapter"
				(path ""
					(reference "R7")
					(unit 1)
				)
			)
			(project "thunderbolt-to-10gbe-adapter"
				(path ""
					(reference "R145")
					(unit 1)
				)
			)
		)
	)
	(symbol
		(lib_id "antmicroTestPoints:TP_0.75mm_SMD")
		(at 133.35 63.5 180)
		(unit 1)
		(exclude_from_sim no)
		(in_bom no)
		(on_board yes)
		(dnp no)
		(property "Reference" "TP23"
			(at 129.032 63.5 0)
			(effects
				(font
					(size 1.27 1.27)
					(thickness 0.15)
				)
				(justify left)
			)
		)
		(property "Value" "TP_0.75mm_SMD"
			(at 123.19 59.69 0)
			(effects
				(font
					(size 1.27 1.27)
					(thickness 0.15)
				)
				(justify left bottom)
				(hide yes)
			)
		)
		(property "Footprint" "antmicro-footprints:TP_SMD_0.75mm"
			(at 123.19 57.15 0)
			(effects
				(font
					(size 1.27 1.27)
					(thickness 0.15)
				)
				(justify left bottom)
				(hide yes)
			)
		)
		(property "Datasheet" ""
			(at 115.57 50.8 0)
			(effects
				(font
					(size 1.27 1.27)
					(thickness 0.15)
				)
				(justify left bottom)
				(hide yes)
			)
		)
		(property "Description" "SMT test point"
			(at 133.35 63.5 0)
			(effects
				(font
					(size 1.27 1.27)
				)
				(hide yes)
			)
		)
		(property "MPN" ""
			(at 122.555 52.07 0)
			(effects
				(font
					(size 1.27 1.27)
					(thickness 0.15)
				)
				(justify left bottom)
				(hide yes)
			)
		)
		(property "Manufacturer" ""
			(at 122.555 57.15 0)
			(effects
				(font
					(size 1.27 1.27)
					(thickness 0.15)
				)
				(justify left bottom)
				(hide yes)
			)
		)
		(property "Author" "Antmicro"
			(at 123.19 54.61 0)
			(effects
				(font
					(size 1.27 1.27)
					(thickness 0.15)
				)
				(justify left bottom)
				(hide yes)
			)
		)
		(property "License" "Apache-2.0"
			(at 123.19 52.07 0)
			(effects
				(font
					(size 1.27 1.27)
					(thickness 0.15)
				)
				(justify left bottom)
				(hide yes)
			)
		)
		(pin "1"
		)
		(instances
			(project "OCuLink to 10GbE adapter"
				(path ""
					(reference "TP3")
					(unit 1)
				)
			)
			(project "thunderbolt-to-10gbe-adapter"
				(path ""
					(reference "TP23")
					(unit 1)
				)
			)
		)
	)
	(symbol
		(lib_id "antmicroResistors0402:R_100R_0402")
		(at 176.53 137.16 90)
		(unit 1)
		(exclude_from_sim no)
		(in_bom yes)
		(on_board yes)
		(dnp yes)
		(property "Reference" "R155"
			(at 178.054 133.35 90)
			(effects
				(font
					(size 1.27 1.27)
					(thickness 0.15)
				)
				(justify right)
			)
		)
		(property "Value" "R_100R_0402"
			(at 189.23 116.84 0)
			(effects
				(font
					(size 1.27 1.27)
					(thickness 0.15)
				)
				(justify left bottom)
				(hide yes)
			)
		)
		(property "Footprint" "antmicro-footprints:R_0402_1005Metric"
			(at 191.77 116.84 0)
			(effects
				(font
					(size 1.27 1.27)
					(thickness 0.15)
				)
				(justify left bottom)
				(hide yes)
			)
		)
		(property "Datasheet" "https://www.bourns.com/docs/product-datasheets/cr.pdf"
			(at 194.31 116.84 0)
			(effects
				(font
					(size 1.27 1.27)
					(thickness 0.15)
				)
				(justify left bottom)
				(hide yes)
			)
		)
		(property "Description" "SMD Chip Resistor, 100 ohm, ± 1%, 62.5 mW, 0402 [1005 Metric], Thick Film, General Purpose"
			(at 176.53 137.16 0)
			(effects
				(font
					(size 1.27 1.27)
				)
				(hide yes)
			)
		)
		(property "MPN" "CR0402-FX-1000GLF"
			(at 196.85 116.84 0)
			(effects
				(font
					(size 1.27 1.27)
					(thickness 0.15)
				)
				(justify left bottom)
				(hide yes)
			)
		)
		(property "Manufacturer" "Bourns"
			(at 199.39 116.84 0)
			(effects
				(font
					(size 1.27 1.27)
					(thickness 0.15)
				)
				(justify left bottom)
				(hide yes)
			)
		)
		(property "License" "Apache-2.0"
			(at 201.93 116.84 0)
			(effects
				(font
					(size 1.27 1.27)
					(thickness 0.15)
				)
				(justify left bottom)
				(hide yes)
			)
		)
		(property "Author" "Antmicro"
			(at 204.47 116.84 0)
			(effects
				(font
					(size 1.27 1.27)
					(thickness 0.15)
				)
				(justify left bottom)
				(hide yes)
			)
		)
		(property "Val" "100R"
			(at 178.054 135.89 90)
			(effects
				(font
					(size 1.27 1.27)
					(thickness 0.15)
				)
				(justify right)
			)
		)
		(property "Tolerance" "1%"
			(at 186.69 116.84 0)
			(effects
				(font
					(size 1.27 1.27)
				)
				(justify left bottom)
				(hide yes)
			)
		)
		(pin "2"
		)
		(pin "1"
		)
		(instances
			(project "OCuLink to 10GbE adapter"
				(path ""
					(reference "R107")
					(unit 1)
				)
			)
			(project "thunderbolt-to-10gbe-adapter"
				(path ""
					(reference "R155")
					(unit 1)
				)
			)
		)
	)
	(symbol
		(lib_id "antmicroResistors0402:R_10k_0402")
		(at 186.69 111.76 90)
		(unit 1)
		(exclude_from_sim no)
		(in_bom yes)
		(on_board yes)
		(dnp no)
		(property "Reference" "R159"
			(at 187.96 107.95 90)
			(effects
				(font
					(size 1.27 1.27)
					(thickness 0.15)
				)
				(justify right)
			)
		)
		(property "Value" "R_10k_0402"
			(at 199.39 91.44 0)
			(effects
				(font
					(size 1.27 1.27)
					(thickness 0.15)
				)
				(justify left bottom)
				(hide yes)
			)
		)
		(property "Footprint" "antmicro-footprints:R_0402_1005Metric"
			(at 201.93 91.44 0)
			(effects
				(font
					(size 1.27 1.27)
					(thickness 0.15)
				)
				(justify left bottom)
				(hide yes)
			)
		)
		(property "Datasheet" "https://www.bourns.com/docs/product-datasheets/cr.pdf"
			(at 204.47 91.44 0)
			(effects
				(font
					(size 1.27 1.27)
					(thickness 0.15)
				)
				(justify left bottom)
				(hide yes)
			)
		)
		(property "Description" "SMD Chip Resistor, 10 kohm, ± 1%, 62.5 mW, 0402 [1005 Metric], Thick Film, General Purpose"
			(at 186.69 111.76 0)
			(effects
				(font
					(size 1.27 1.27)
				)
				(hide yes)
			)
		)
		(property "MPN" "CR0402-FX-1002GLF"
			(at 207.01 91.44 0)
			(effects
				(font
					(size 1.27 1.27)
					(thickness 0.15)
				)
				(justify left bottom)
				(hide yes)
			)
		)
		(property "Manufacturer" "Bourns"
			(at 209.55 91.44 0)
			(effects
				(font
					(size 1.27 1.27)
					(thickness 0.15)
				)
				(justify left bottom)
				(hide yes)
			)
		)
		(property "License" "Apache-2.0"
			(at 212.09 91.44 0)
			(effects
				(font
					(size 1.27 1.27)
					(thickness 0.15)
				)
				(justify left bottom)
				(hide yes)
			)
		)
		(property "Author" "Antmicro"
			(at 214.63 91.44 0)
			(effects
				(font
					(size 1.27 1.27)
					(thickness 0.15)
				)
				(justify left bottom)
				(hide yes)
			)
		)
		(property "Val" "10k"
			(at 187.96 110.49 90)
			(effects
				(font
					(size 1.27 1.27)
					(thickness 0.15)
				)
				(justify right)
			)
		)
		(property "Tolerance" "1%"
			(at 196.85 91.44 0)
			(effects
				(font
					(size 1.27 1.27)
				)
				(justify left bottom)
				(hide yes)
			)
		)
		(pin "2"
		)
		(pin "1"
		)
		(instances
			(project "OCuLink to 10GbE adapter"
				(path ""
					(reference "R99")
					(unit 1)
				)
			)
			(project "thunderbolt-to-10gbe-adapter"
				(path ""
					(reference "R159")
					(unit 1)
				)
			)
		)
	)
	(symbol
		(lib_id "antmicroResistors0402:R_100k_0402")
		(at 160.02 55.88 90)
		(unit 1)
		(exclude_from_sim no)
		(in_bom yes)
		(on_board yes)
		(dnp no)
		(property "Reference" "R147"
			(at 161.544 52.07 90)
			(effects
				(font
					(size 1.27 1.27)
					(thickness 0.15)
				)
				(justify right)
			)
		)
		(property "Value" "R_100k_0402"
			(at 172.72 35.56 0)
			(effects
				(font
					(size 1.27 1.27)
					(thickness 0.15)
				)
				(justify left bottom)
				(hide yes)
			)
		)
		(property "Footprint" "antmicro-footprints:R_0402_1005Metric"
			(at 175.26 35.56 0)
			(effects
				(font
					(size 1.27 1.27)
					(thickness 0.15)
				)
				(justify left bottom)
				(hide yes)
			)
		)
		(property "Datasheet" "https://www.bourns.com/docs/product-datasheets/cr.pdf"
			(at 177.8 35.56 0)
			(effects
				(font
					(size 1.27 1.27)
					(thickness 0.15)
				)
				(justify left bottom)
				(hide yes)
			)
		)
		(property "Description" "SMD Chip Resistor, 100 kohm, ± 1%, 62.5 mW, 0402 [1005 Metric], Thick Film, General Purpose"
			(at 160.02 55.88 0)
			(effects
				(font
					(size 1.27 1.27)
				)
				(hide yes)
			)
		)
		(property "MPN" "CR0402-FX-1003GLF"
			(at 180.34 35.56 0)
			(effects
				(font
					(size 1.27 1.27)
					(thickness 0.15)
				)
				(justify left bottom)
				(hide yes)
			)
		)
		(property "Manufacturer" "Bourns"
			(at 182.88 35.56 0)
			(effects
				(font
					(size 1.27 1.27)
					(thickness 0.15)
				)
				(justify left bottom)
				(hide yes)
			)
		)
		(property "License" "Apache-2.0"
			(at 185.42 35.56 0)
			(effects
				(font
					(size 1.27 1.27)
					(thickness 0.15)
				)
				(justify left bottom)
				(hide yes)
			)
		)
		(property "Author" "Antmicro"
			(at 187.96 35.56 0)
			(effects
				(font
					(size 1.27 1.27)
					(thickness 0.15)
				)
				(justify left bottom)
				(hide yes)
			)
		)
		(property "Val" "100k"
			(at 161.544 54.61 90)
			(effects
				(font
					(size 1.27 1.27)
					(thickness 0.15)
				)
				(justify right)
			)
		)
		(property "Tolerance" "1%"
			(at 170.18 35.56 0)
			(effects
				(font
					(size 1.27 1.27)
				)
				(justify left bottom)
				(hide yes)
			)
		)
		(pin "2"
		)
		(pin "1"
		)
		(instances
			(project "OCuLink to 10GbE adapter"
				(path ""
					(reference "R79")
					(unit 1)
				)
			)
			(project "thunderbolt-to-10gbe-adapter"
				(path ""
					(reference "R147")
					(unit 1)
				)
			)
		)
	)
	(symbol
		(lib_id "antmicropower:+1V8")
		(at 213.36 182.88 0)
		(unit 1)
		(exclude_from_sim no)
		(in_bom yes)
		(on_board yes)
		(dnp no)
		(property "Reference" "#PWR0407"
			(at 228.6 185.42 0)
			(effects
				(font
					(size 1.27 1.27)
					(thickness 0.15)
				)
				(justify left bottom)
				(hide yes)
			)
		)
		(property "Value" "+1V88"
			(at 213.36 179.07 0)
			(effects
				(font
					(size 1.27 1.27)
					(thickness 0.15)
				)
			)
		)
		(property "Footprint" ""
			(at 228.6 190.5 0)
			(effects
				(font
					(size 1.27 1.27)
					(thickness 0.15)
				)
				(justify left bottom)
				(hide yes)
			)
		)
		(property "Datasheet" ""
			(at 228.6 193.04 0)
			(effects
				(font
					(size 1.27 1.27)
					(thickness 0.15)
				)
				(justify left bottom)
				(hide yes)
			)
		)
		(property "Description" ""
			(at 213.36 182.88 0)
			(effects
				(font
					(size 1.27 1.27)
				)
				(hide yes)
			)
		)
		(property "Author" "Antmicro"
			(at 228.6 187.96 0)
			(effects
				(font
					(size 1.27 1.27)
					(thickness 0.15)
				)
				(justify left bottom)
				(hide yes)
			)
		)
		(property "License" "Apache-2.0"
			(at 228.6 190.5 0)
			(effects
				(font
					(size 1.27 1.27)
					(thickness 0.15)
				)
				(justify left bottom)
				(hide yes)
			)
		)
		(pin "1"
		)
		(instances
			(project "OCuLink to 10GbE adapter"
				(path ""
					(reference "#PWR0277")
					(unit 1)
				)
			)
			(project "thunderbolt-to-10gbe-adapter"
				(path ""
					(reference "#PWR0407")
					(unit 1)
				)
			)
		)
	)
	(symbol
		(lib_id "antmicroResistors0402:R_22R_0402")
		(at 294.64 124.46 0)
		(unit 1)
		(exclude_from_sim no)
		(in_bom yes)
		(on_board yes)
		(dnp no)
		(property "Reference" "R178"
			(at 294.894 123.444 0)
			(effects
				(font
					(size 1.27 1.27)
					(thickness 0.15)
				)
				(justify right)
			)
		)
		(property "Value" "R_22R_0402"
			(at 314.96 137.16 0)
			(effects
				(font
					(size 1.27 1.27)
					(thickness 0.15)
				)
				(justify left bottom)
				(hide yes)
			)
		)
		(property "Footprint" "antmicro-footprints:R_0402_1005Metric"
			(at 314.96 139.7 0)
			(effects
				(font
					(size 1.27 1.27)
					(thickness 0.15)
				)
				(justify left bottom)
				(hide yes)
			)
		)
		(property "Datasheet" "https://www.bourns.com/docs/product-datasheets/cr.pdf"
			(at 314.96 142.24 0)
			(effects
				(font
					(size 1.27 1.27)
					(thickness 0.15)
				)
				(justify left bottom)
				(hide yes)
			)
		)
		(property "Description" "SMD Chip Resistor, 22 ohm, ± 1%, 62.5 mW, 0402 [1005 Metric], Thick Film, General Purpose"
			(at 294.64 124.46 0)
			(effects
				(font
					(size 1.27 1.27)
				)
				(hide yes)
			)
		)
		(property "MPN" "CR0402-FX-22R0GLF"
			(at 314.96 144.78 0)
			(effects
				(font
					(size 1.27 1.27)
					(thickness 0.15)
				)
				(justify left bottom)
				(hide yes)
			)
		)
		(property "Manufacturer" "Bourns"
			(at 314.96 147.32 0)
			(effects
				(font
					(size 1.27 1.27)
					(thickness 0.15)
				)
				(justify left bottom)
				(hide yes)
			)
		)
		(property "License" "Apache-2.0"
			(at 314.96 149.86 0)
			(effects
				(font
					(size 1.27 1.27)
					(thickness 0.15)
				)
				(justify left bottom)
				(hide yes)
			)
		)
		(property "Author" "Antmicro"
			(at 314.96 152.4 0)
			(effects
				(font
					(size 1.27 1.27)
					(thickness 0.15)
				)
				(justify left bottom)
				(hide yes)
			)
		)
		(property "Val" "22R"
			(at 299.72 123.19 0)
			(effects
				(font
					(size 1.27 1.27)
					(thickness 0.15)
				)
				(justify left)
			)
		)
		(property "Tolerance" "1%"
			(at 314.96 134.62 0)
			(effects
				(font
					(size 1.27 1.27)
				)
				(justify left bottom)
				(hide yes)
			)
		)
		(pin "2"
		)
		(pin "1"
		)
		(instances
			(project ""
				(path ""
					(reference "R102")
					(unit 1)
				)
			)
			(project "thunderbolt-to-10gbe-adapter"
				(path ""
					(reference "R178")
					(unit 1)
				)
			)
		)
	)
	(symbol
		(lib_id "antmicroResonators:Resonator_50MHz_XRCGE")
		(at 156.21 170.18 0)
		(unit 1)
		(exclude_from_sim no)
		(in_bom yes)
		(on_board yes)
		(dnp no)
		(property "Reference" "Y3"
			(at 160.528 159.258 0)
			(effects
				(font
					(size 1.27 1.27)
					(thickness 0.15)
				)
			)
		)
		(property "Value" "Resonator_50MHz_XRCGE"
			(at 179.07 177.8 0)
			(effects
				(font
					(size 1.27 1.27)
					(thickness 0.15)
				)
				(justify left bottom)
				(hide yes)
			)
		)
		(property "Footprint" "antmicro-footprints:Resonator_SMD_Murata_XRCGB_2x1.6x0.65mm"
			(at 179.07 180.34 0)
			(effects
				(font
					(size 1.27 1.27)
					(thickness 0.15)
				)
				(justify left bottom)
				(hide yes)
			)
		)
		(property "Datasheet" "https://www.murata.com/products/productdata/8813268205598/SPEC-XRCGE50M000F5A2AR0.pdf"
			(at 179.07 182.88 0)
			(effects
				(font
					(size 1.27 1.27)
					(thickness 0.15)
				)
				(justify left bottom)
				(hide yes)
			)
		)
		(property "Description" "Crystal, 50 MHz, 2mm x 1.6mm, 50 ppm, 4.7 pF, 50 ppm, XRCGE Series"
			(at 156.21 170.18 0)
			(effects
				(font
					(size 1.27 1.27)
				)
				(hide yes)
			)
		)
		(property "Manufacturer" "Murata"
			(at 179.07 195.58 0)
			(effects
				(font
					(size 1.27 1.27)
				)
				(justify left bottom)
				(hide yes)
			)
		)
		(property "MPN" "XRCGE50M000F5A2AR0"
			(at 160.528 161.798 0)
			(effects
				(font
					(size 1.27 1.27)
				)
			)
		)
		(property "Val" "50MHz"
			(at 160.528 164.338 0)
			(effects
				(font
					(size 1.27 1.27)
				)
			)
		)
		(property "CLoad" "4.7pF"
			(at 179.07 190.5 0)
			(effects
				(font
					(size 1.27 1.27)
				)
				(justify left bottom)
				(hide yes)
			)
		)
		(property "Author" "Antmicro"
			(at 179.07 185.42 0)
			(effects
				(font
					(size 1.27 1.27)
				)
				(justify left bottom)
				(hide yes)
			)
		)
		(property "License" "Apache-2.0"
			(at 179.07 187.96 0)
			(effects
				(font
					(size 1.27 1.27)
				)
				(justify left bottom)
				(hide yes)
			)
		)
		(pin "4"
		)
		(pin "2"
		)
		(pin "3"
		)
		(pin "1"
		)
		(instances
			(project "OCuLink to 10GbE adapter"
				(path ""
					(reference "Y2")
					(unit 1)
				)
			)
			(project "thunderbolt-to-10gbe-adapter"
				(path ""
					(reference "Y3")
					(unit 1)
				)
			)
		)
	)
	(symbol
		(lib_id "antmicropower:GND")
		(at 165.1 139.7 0)
		(unit 1)
		(exclude_from_sim no)
		(in_bom yes)
		(on_board yes)
		(dnp no)
		(property "Reference" "#PWR0393"
			(at 173.99 142.24 0)
			(effects
				(font
					(size 1.27 1.27)
					(thickness 0.15)
				)
				(justify left bottom)
				(hide yes)
			)
		)
		(property "Value" "GND"
			(at 165.1 143.51 0)
			(effects
				(font
					(size 1.27 1.27)
					(thickness 0.15)
				)
			)
		)
		(property "Footprint" ""
			(at 173.99 147.32 0)
			(effects
				(font
					(size 1.27 1.27)
					(thickness 0.15)
				)
				(justify left bottom)
				(hide yes)
			)
		)
		(property "Datasheet" ""
			(at 173.99 152.4 0)
			(effects
				(font
					(size 1.27 1.27)
					(thickness 0.15)
				)
				(justify left bottom)
				(hide yes)
			)
		)
		(property "Description" ""
			(at 165.1 139.7 0)
			(effects
				(font
					(size 1.27 1.27)
				)
				(hide yes)
			)
		)
		(property "Author" "Antmicro"
			(at 173.99 147.32 0)
			(effects
				(font
					(size 1.27 1.27)
					(thickness 0.15)
				)
				(justify left bottom)
				(hide yes)
			)
		)
		(property "License" "Apache-2.0"
			(at 173.99 149.86 0)
			(effects
				(font
					(size 1.27 1.27)
					(thickness 0.15)
				)
				(justify left bottom)
				(hide yes)
			)
		)
		(pin "1"
		)
		(instances
			(project "OCuLink to 10GbE adapter"
				(path ""
					(reference "#PWR0270")
					(unit 1)
				)
			)
			(project "thunderbolt-to-10gbe-adapter"
				(path ""
					(reference "#PWR0393")
					(unit 1)
				)
			)
		)
	)
	(symbol
		(lib_id "antmicropower:GND")
		(at 190.5 254 0)
		(unit 1)
		(exclude_from_sim no)
		(in_bom yes)
		(on_board yes)
		(dnp no)
		(property "Reference" "#PWR0404"
			(at 199.39 256.54 0)
			(effects
				(font
					(size 1.27 1.27)
					(thickness 0.15)
				)
				(justify left bottom)
				(hide yes)
			)
		)
		(property "Value" "GND"
			(at 190.5 257.81 0)
			(effects
				(font
					(size 1.27 1.27)
					(thickness 0.15)
				)
			)
		)
		(property "Footprint" ""
			(at 199.39 261.62 0)
			(effects
				(font
					(size 1.27 1.27)
					(thickness 0.15)
				)
				(justify left bottom)
				(hide yes)
			)
		)
		(property "Datasheet" ""
			(at 199.39 266.7 0)
			(effects
				(font
					(size 1.27 1.27)
					(thickness 0.15)
				)
				(justify left bottom)
				(hide yes)
			)
		)
		(property "Description" ""
			(at 190.5 254 0)
			(effects
				(font
					(size 1.27 1.27)
				)
				(hide yes)
			)
		)
		(property "Author" "Antmicro"
			(at 199.39 261.62 0)
			(effects
				(font
					(size 1.27 1.27)
					(thickness 0.15)
				)
				(justify left bottom)
				(hide yes)
			)
		)
		(property "License" "Apache-2.0"
			(at 199.39 264.16 0)
			(effects
				(font
					(size 1.27 1.27)
					(thickness 0.15)
				)
				(justify left bottom)
				(hide yes)
			)
		)
		(pin "1"
		)
		(instances
			(project "OCuLink to 10GbE adapter"
				(path ""
					(reference "#PWR0282")
					(unit 1)
				)
			)
			(project "thunderbolt-to-10gbe-adapter"
				(path ""
					(reference "#PWR0404")
					(unit 1)
				)
			)
		)
	)
	(symbol
		(lib_id "antmicroResistors0402:R_100k_0402")
		(at 162.56 86.36 90)
		(unit 1)
		(exclude_from_sim no)
		(in_bom yes)
		(on_board yes)
		(dnp no)
		(property "Reference" "R148"
			(at 164.084 82.55 90)
			(effects
				(font
					(size 1.27 1.27)
					(thickness 0.15)
				)
				(justify right)
			)
		)
		(property "Value" "R_100k_0402"
			(at 175.26 66.04 0)
			(effects
				(font
					(size 1.27 1.27)
					(thickness 0.15)
				)
				(justify left bottom)
				(hide yes)
			)
		)
		(property "Footprint" "antmicro-footprints:R_0402_1005Metric"
			(at 177.8 66.04 0)
			(effects
				(font
					(size 1.27 1.27)
					(thickness 0.15)
				)
				(justify left bottom)
				(hide yes)
			)
		)
		(property "Datasheet" "https://www.bourns.com/docs/product-datasheets/cr.pdf"
			(at 180.34 66.04 0)
			(effects
				(font
					(size 1.27 1.27)
					(thickness 0.15)
				)
				(justify left bottom)
				(hide yes)
			)
		)
		(property "Description" "SMD Chip Resistor, 100 kohm, ± 1%, 62.5 mW, 0402 [1005 Metric], Thick Film, General Purpose"
			(at 162.56 86.36 0)
			(effects
				(font
					(size 1.27 1.27)
				)
				(hide yes)
			)
		)
		(property "MPN" "CR0402-FX-1003GLF"
			(at 182.88 66.04 0)
			(effects
				(font
					(size 1.27 1.27)
					(thickness 0.15)
				)
				(justify left bottom)
				(hide yes)
			)
		)
		(property "Manufacturer" "Bourns"
			(at 185.42 66.04 0)
			(effects
				(font
					(size 1.27 1.27)
					(thickness 0.15)
				)
				(justify left bottom)
				(hide yes)
			)
		)
		(property "License" "Apache-2.0"
			(at 187.96 66.04 0)
			(effects
				(font
					(size 1.27 1.27)
					(thickness 0.15)
				)
				(justify left bottom)
				(hide yes)
			)
		)
		(property "Author" "Antmicro"
			(at 190.5 66.04 0)
			(effects
				(font
					(size 1.27 1.27)
					(thickness 0.15)
				)
				(justify left bottom)
				(hide yes)
			)
		)
		(property "Val" "100k"
			(at 164.084 85.09 90)
			(effects
				(font
					(size 1.27 1.27)
					(thickness 0.15)
				)
				(justify right)
			)
		)
		(property "Tolerance" "1%"
			(at 172.72 66.04 0)
			(effects
				(font
					(size 1.27 1.27)
				)
				(justify left bottom)
				(hide yes)
			)
		)
		(pin "2"
		)
		(pin "1"
		)
		(instances
			(project "OCuLink to 10GbE adapter"
				(path ""
					(reference "R87")
					(unit 1)
				)
			)
			(project "thunderbolt-to-10gbe-adapter"
				(path ""
					(reference "R148")
					(unit 1)
				)
			)
		)
	)
	(symbol
		(lib_id "antmicropower:GND")
		(at 199.39 254 0)
		(unit 1)
		(exclude_from_sim no)
		(in_bom yes)
		(on_board yes)
		(dnp no)
		(property "Reference" "#PWR0406"
			(at 208.28 256.54 0)
			(effects
				(font
					(size 1.27 1.27)
					(thickness 0.15)
				)
				(justify left bottom)
				(hide yes)
			)
		)
		(property "Value" "GND"
			(at 199.39 257.81 0)
			(effects
				(font
					(size 1.27 1.27)
					(thickness 0.15)
				)
			)
		)
		(property "Footprint" ""
			(at 208.28 261.62 0)
			(effects
				(font
					(size 1.27 1.27)
					(thickness 0.15)
				)
				(justify left bottom)
				(hide yes)
			)
		)
		(property "Datasheet" ""
			(at 208.28 266.7 0)
			(effects
				(font
					(size 1.27 1.27)
					(thickness 0.15)
				)
				(justify left bottom)
				(hide yes)
			)
		)
		(property "Description" ""
			(at 199.39 254 0)
			(effects
				(font
					(size 1.27 1.27)
				)
				(hide yes)
			)
		)
		(property "Author" "Antmicro"
			(at 208.28 261.62 0)
			(effects
				(font
					(size 1.27 1.27)
					(thickness 0.15)
				)
				(justify left bottom)
				(hide yes)
			)
		)
		(property "License" "Apache-2.0"
			(at 208.28 264.16 0)
			(effects
				(font
					(size 1.27 1.27)
					(thickness 0.15)
				)
				(justify left bottom)
				(hide yes)
			)
		)
		(pin "1"
		)
		(instances
			(project "OCuLink to 10GbE adapter"
				(path ""
					(reference "#PWR0283")
					(unit 1)
				)
			)
			(project "thunderbolt-to-10gbe-adapter"
				(path ""
					(reference "#PWR0406")
					(unit 1)
				)
			)
		)
	)
	(symbol
		(lib_id "antmicroTestPoints:TP_0.75mm_SMD")
		(at 133.35 73.66 180)
		(unit 1)
		(exclude_from_sim no)
		(in_bom no)
		(on_board yes)
		(dnp no)
		(property "Reference" "TP27"
			(at 129.032 73.66 0)
			(effects
				(font
					(size 1.27 1.27)
					(thickness 0.15)
				)
				(justify left)
			)
		)
		(property "Value" "TP_0.75mm_SMD"
			(at 123.19 69.85 0)
			(effects
				(font
					(size 1.27 1.27)
					(thickness 0.15)
				)
				(justify left bottom)
				(hide yes)
			)
		)
		(property "Footprint" "antmicro-footprints:TP_SMD_0.75mm"
			(at 123.19 67.31 0)
			(effects
				(font
					(size 1.27 1.27)
					(thickness 0.15)
				)
				(justify left bottom)
				(hide yes)
			)
		)
		(property "Datasheet" ""
			(at 115.57 60.96 0)
			(effects
				(font
					(size 1.27 1.27)
					(thickness 0.15)
				)
				(justify left bottom)
				(hide yes)
			)
		)
		(property "Description" "SMT test point"
			(at 133.35 73.66 0)
			(effects
				(font
					(size 1.27 1.27)
				)
				(hide yes)
			)
		)
		(property "MPN" ""
			(at 122.555 62.23 0)
			(effects
				(font
					(size 1.27 1.27)
					(thickness 0.15)
				)
				(justify left bottom)
				(hide yes)
			)
		)
		(property "Manufacturer" ""
			(at 122.555 67.31 0)
			(effects
				(font
					(size 1.27 1.27)
					(thickness 0.15)
				)
				(justify left bottom)
				(hide yes)
			)
		)
		(property "Author" "Antmicro"
			(at 123.19 64.77 0)
			(effects
				(font
					(size 1.27 1.27)
					(thickness 0.15)
				)
				(justify left bottom)
				(hide yes)
			)
		)
		(property "License" "Apache-2.0"
			(at 123.19 62.23 0)
			(effects
				(font
					(size 1.27 1.27)
					(thickness 0.15)
				)
				(justify left bottom)
				(hide yes)
			)
		)
		(pin "1"
		)
		(instances
			(project "OCuLink to 10GbE adapter"
				(path ""
					(reference "TP7")
					(unit 1)
				)
			)
			(project "thunderbolt-to-10gbe-adapter"
				(path ""
					(reference "TP27")
					(unit 1)
				)
			)
		)
	)
	(symbol
		(lib_id "antmicroTestPoints:TP_0.75mm_SMD")
		(at 210.82 241.3 180)
		(unit 1)
		(exclude_from_sim no)
		(in_bom no)
		(on_board yes)
		(dnp no)
		(property "Reference" "TP34"
			(at 206.502 241.3 0)
			(effects
				(font
					(size 1.27 1.27)
					(thickness 0.15)
				)
				(justify left)
			)
		)
		(property "Value" "TP_0.75mm_SMD"
			(at 200.66 237.49 0)
			(effects
				(font
					(size 1.27 1.27)
					(thickness 0.15)
				)
				(justify left bottom)
				(hide yes)
			)
		)
		(property "Footprint" "antmicro-footprints:TP_SMD_0.75mm"
			(at 200.66 234.95 0)
			(effects
				(font
					(size 1.27 1.27)
					(thickness 0.15)
				)
				(justify left bottom)
				(hide yes)
			)
		)
		(property "Datasheet" ""
			(at 193.04 228.6 0)
			(effects
				(font
					(size 1.27 1.27)
					(thickness 0.15)
				)
				(justify left bottom)
				(hide yes)
			)
		)
		(property "Description" "SMT test point"
			(at 210.82 241.3 0)
			(effects
				(font
					(size 1.27 1.27)
				)
				(hide yes)
			)
		)
		(property "MPN" ""
			(at 200.025 229.87 0)
			(effects
				(font
					(size 1.27 1.27)
					(thickness 0.15)
				)
				(justify left bottom)
				(hide yes)
			)
		)
		(property "Manufacturer" ""
			(at 200.025 234.95 0)
			(effects
				(font
					(size 1.27 1.27)
					(thickness 0.15)
				)
				(justify left bottom)
				(hide yes)
			)
		)
		(property "Author" "Antmicro"
			(at 200.66 232.41 0)
			(effects
				(font
					(size 1.27 1.27)
					(thickness 0.15)
				)
				(justify left bottom)
				(hide yes)
			)
		)
		(property "License" "Apache-2.0"
			(at 200.66 229.87 0)
			(effects
				(font
					(size 1.27 1.27)
					(thickness 0.15)
				)
				(justify left bottom)
				(hide yes)
			)
		)
		(pin "1"
		)
		(instances
			(project "OCuLink to 10GbE adapter"
				(path ""
					(reference "TP13")
					(unit 1)
				)
			)
			(project "thunderbolt-to-10gbe-adapter"
				(path ""
					(reference "TP34")
					(unit 1)
				)
			)
		)
	)
	(symbol
		(lib_id "antmicroResistors0402:R_100k_0402")
		(at 151.13 55.88 90)
		(unit 1)
		(exclude_from_sim no)
		(in_bom yes)
		(on_board yes)
		(dnp no)
		(property "Reference" "R144"
			(at 152.654 52.07 90)
			(effects
				(font
					(size 1.27 1.27)
					(thickness 0.15)
				)
				(justify right)
			)
		)
		(property "Value" "R_100k_0402"
			(at 163.83 35.56 0)
			(effects
				(font
					(size 1.27 1.27)
					(thickness 0.15)
				)
				(justify left bottom)
				(hide yes)
			)
		)
		(property "Footprint" "antmicro-footprints:R_0402_1005Metric"
			(at 166.37 35.56 0)
			(effects
				(font
					(size 1.27 1.27)
					(thickness 0.15)
				)
				(justify left bottom)
				(hide yes)
			)
		)
		(property "Datasheet" "https://www.bourns.com/docs/product-datasheets/cr.pdf"
			(at 168.91 35.56 0)
			(effects
				(font
					(size 1.27 1.27)
					(thickness 0.15)
				)
				(justify left bottom)
				(hide yes)
			)
		)
		(property "Description" "SMD Chip Resistor, 100 kohm, ± 1%, 62.5 mW, 0402 [1005 Metric], Thick Film, General Purpose"
			(at 151.13 55.88 0)
			(effects
				(font
					(size 1.27 1.27)
				)
				(hide yes)
			)
		)
		(property "MPN" "CR0402-FX-1003GLF"
			(at 171.45 35.56 0)
			(effects
				(font
					(size 1.27 1.27)
					(thickness 0.15)
				)
				(justify left bottom)
				(hide yes)
			)
		)
		(property "Manufacturer" "Bourns"
			(at 173.99 35.56 0)
			(effects
				(font
					(size 1.27 1.27)
					(thickness 0.15)
				)
				(justify left bottom)
				(hide yes)
			)
		)
		(property "License" "Apache-2.0"
			(at 176.53 35.56 0)
			(effects
				(font
					(size 1.27 1.27)
					(thickness 0.15)
				)
				(justify left bottom)
				(hide yes)
			)
		)
		(property "Author" "Antmicro"
			(at 179.07 35.56 0)
			(effects
				(font
					(size 1.27 1.27)
					(thickness 0.15)
				)
				(justify left bottom)
				(hide yes)
			)
		)
		(property "Val" "100k"
			(at 152.654 54.61 90)
			(effects
				(font
					(size 1.27 1.27)
					(thickness 0.15)
				)
				(justify right)
			)
		)
		(property "Tolerance" "1%"
			(at 161.29 35.56 0)
			(effects
				(font
					(size 1.27 1.27)
				)
				(justify left bottom)
				(hide yes)
			)
		)
		(pin "2"
		)
		(pin "1"
		)
		(instances
			(project "OCuLink to 10GbE adapter"
				(path ""
					(reference "R78")
					(unit 1)
				)
			)
			(project "thunderbolt-to-10gbe-adapter"
				(path ""
					(reference "R144")
					(unit 1)
				)
			)
		)
	)
	(symbol
		(lib_id "antmicroResistors0402:R_1k_0402")
		(at 281.94 165.1 270)
		(mirror x)
		(unit 1)
		(exclude_from_sim no)
		(in_bom yes)
		(on_board yes)
		(dnp no)
		(property "Reference" "R175"
			(at 280.416 161.29 90)
			(effects
				(font
					(size 1.27 1.27)
					(thickness 0.15)
				)
				(justify right)
			)
		)
		(property "Value" "R_1k_0402"
			(at 269.24 144.78 0)
			(effects
				(font
					(size 1.27 1.27)
					(thickness 0.15)
				)
				(justify left bottom)
				(hide yes)
			)
		)
		(property "Footprint" "antmicro-footprints:R_0402_1005Metric"
			(at 266.7 144.78 0)
			(effects
				(font
					(size 1.27 1.27)
					(thickness 0.15)
				)
				(justify left bottom)
				(hide yes)
			)
		)
		(property "Datasheet" "https://www.bourns.com/docs/product-datasheets/cr.pdf"
			(at 264.16 144.78 0)
			(effects
				(font
					(size 1.27 1.27)
					(thickness 0.15)
				)
				(justify left bottom)
				(hide yes)
			)
		)
		(property "Description" "SMD Chip Resistor, 1 kohm, ± 1%, 63 mW, 0402 [1005 Metric], Thick Film, General Purpose"
			(at 281.94 165.1 0)
			(effects
				(font
					(size 1.27 1.27)
				)
				(hide yes)
			)
		)
		(property "MPN" "CR0402-FX-1001GLF"
			(at 261.62 144.78 0)
			(effects
				(font
					(size 1.27 1.27)
					(thickness 0.15)
				)
				(justify left bottom)
				(hide yes)
			)
		)
		(property "Manufacturer" "Bourns"
			(at 259.08 144.78 0)
			(effects
				(font
					(size 1.27 1.27)
					(thickness 0.15)
				)
				(justify left bottom)
				(hide yes)
			)
		)
		(property "License" "Apache-2.0"
			(at 256.54 144.78 0)
			(effects
				(font
					(size 1.27 1.27)
					(thickness 0.15)
				)
				(justify left bottom)
				(hide yes)
			)
		)
		(property "Author" "Antmicro"
			(at 254 144.78 0)
			(effects
				(font
					(size 1.27 1.27)
					(thickness 0.15)
				)
				(justify left bottom)
				(hide yes)
			)
		)
		(property "Val" "1k"
			(at 280.416 163.83 90)
			(effects
				(font
					(size 1.27 1.27)
					(thickness 0.15)
				)
				(justify right)
			)
		)
		(property "Tolerance" "1%"
			(at 271.78 144.78 0)
			(effects
				(font
					(size 1.27 1.27)
				)
				(justify left bottom)
				(hide yes)
			)
		)
		(pin "2"
		)
		(pin "1"
		)
		(instances
			(project "OCuLink to 10GbE adapter"
				(path ""
					(reference "R111")
					(unit 1)
				)
			)
			(project "thunderbolt-to-10gbe-adapter"
				(path ""
					(reference "R175")
					(unit 1)
				)
			)
		)
	)
	(symbol
		(lib_id "antmicroResistors0402:R_100k_0402")
		(at 186.69 55.88 90)
		(unit 1)
		(exclude_from_sim no)
		(in_bom yes)
		(on_board yes)
		(dnp yes)
		(property "Reference" "R158"
			(at 188.214 52.07 90)
			(effects
				(font
					(size 1.27 1.27)
					(thickness 0.15)
				)
				(justify right)
			)
		)
		(property "Value" "R_100k_0402"
			(at 199.39 35.56 0)
			(effects
				(font
					(size 1.27 1.27)
					(thickness 0.15)
				)
				(justify left bottom)
				(hide yes)
			)
		)
		(property "Footprint" "antmicro-footprints:R_0402_1005Metric"
			(at 201.93 35.56 0)
			(effects
				(font
					(size 1.27 1.27)
					(thickness 0.15)
				)
				(justify left bottom)
				(hide yes)
			)
		)
		(property "Datasheet" "https://www.bourns.com/docs/product-datasheets/cr.pdf"
			(at 204.47 35.56 0)
			(effects
				(font
					(size 1.27 1.27)
					(thickness 0.15)
				)
				(justify left bottom)
				(hide yes)
			)
		)
		(property "Description" "SMD Chip Resistor, 100 kohm, ± 1%, 62.5 mW, 0402 [1005 Metric], Thick Film, General Purpose"
			(at 186.69 55.88 0)
			(effects
				(font
					(size 1.27 1.27)
				)
				(hide yes)
			)
		)
		(property "MPN" "CR0402-FX-1003GLF"
			(at 207.01 35.56 0)
			(effects
				(font
					(size 1.27 1.27)
					(thickness 0.15)
				)
				(justify left bottom)
				(hide yes)
			)
		)
		(property "Manufacturer" "Bourns"
			(at 209.55 35.56 0)
			(effects
				(font
					(size 1.27 1.27)
					(thickness 0.15)
				)
				(justify left bottom)
				(hide yes)
			)
		)
		(property "License" "Apache-2.0"
			(at 212.09 35.56 0)
			(effects
				(font
					(size 1.27 1.27)
					(thickness 0.15)
				)
				(justify left bottom)
				(hide yes)
			)
		)
		(property "Author" "Antmicro"
			(at 214.63 35.56 0)
			(effects
				(font
					(size 1.27 1.27)
					(thickness 0.15)
				)
				(justify left bottom)
				(hide yes)
			)
		)
		(property "Val" "100k"
			(at 188.214 54.61 90)
			(effects
				(font
					(size 1.27 1.27)
					(thickness 0.15)
				)
				(justify right)
			)
		)
		(property "Tolerance" "1%"
			(at 196.85 35.56 0)
			(effects
				(font
					(size 1.27 1.27)
				)
				(justify left bottom)
				(hide yes)
			)
		)
		(pin "2"
		)
		(pin "1"
		)
		(instances
			(project "OCuLink to 10GbE adapter"
				(path ""
					(reference "R82")
					(unit 1)
				)
			)
			(project "thunderbolt-to-10gbe-adapter"
				(path ""
					(reference "R158")
					(unit 1)
				)
			)
		)
	)
	(symbol
		(lib_id "antmicropower:+1V8")
		(at 138.43 176.53 0)
		(mirror y)
		(unit 1)
		(exclude_from_sim no)
		(in_bom yes)
		(on_board yes)
		(dnp no)
		(property "Reference" "#PWR0384"
			(at 123.19 179.07 0)
			(effects
				(font
					(size 1.27 1.27)
					(thickness 0.15)
				)
				(justify left bottom)
				(hide yes)
			)
		)
		(property "Value" "+1V88"
			(at 138.43 172.72 0)
			(effects
				(font
					(size 1.27 1.27)
					(thickness 0.15)
				)
			)
		)
		(property "Footprint" ""
			(at 123.19 184.15 0)
			(effects
				(font
					(size 1.27 1.27)
					(thickness 0.15)
				)
				(justify left bottom)
				(hide yes)
			)
		)
		(property "Datasheet" ""
			(at 123.19 186.69 0)
			(effects
				(font
					(size 1.27 1.27)
					(thickness 0.15)
				)
				(justify left bottom)
				(hide yes)
			)
		)
		(property "Description" ""
			(at 138.43 176.53 0)
			(effects
				(font
					(size 1.27 1.27)
				)
				(hide yes)
			)
		)
		(property "Author" "Antmicro"
			(at 123.19 181.61 0)
			(effects
				(font
					(size 1.27 1.27)
					(thickness 0.15)
				)
				(justify left bottom)
				(hide yes)
			)
		)
		(property "License" "Apache-2.0"
			(at 123.19 184.15 0)
			(effects
				(font
					(size 1.27 1.27)
					(thickness 0.15)
				)
				(justify left bottom)
				(hide yes)
			)
		)
		(pin "1"
		)
		(instances
			(project "OCuLink to 10GbE adapter"
				(path ""
					(reference "#PWR0106")
					(unit 1)
				)
			)
			(project "thunderbolt-to-10gbe-adapter"
				(path ""
					(reference "#PWR0384")
					(unit 1)
				)
			)
		)
	)
	(symbol
		(lib_id "antmicroTestPoints:TP_0.75mm_SMD")
		(at 133.35 71.12 180)
		(unit 1)
		(exclude_from_sim no)
		(in_bom no)
		(on_board yes)
		(dnp no)
		(property "Reference" "TP26"
			(at 129.032 71.12 0)
			(effects
				(font
					(size 1.27 1.27)
					(thickness 0.15)
				)
				(justify left)
			)
		)
		(property "Value" "TP_0.75mm_SMD"
			(at 123.19 67.31 0)
			(effects
				(font
					(size 1.27 1.27)
					(thickness 0.15)
				)
				(justify left bottom)
				(hide yes)
			)
		)
		(property "Footprint" "antmicro-footprints:TP_SMD_0.75mm"
			(at 123.19 64.77 0)
			(effects
				(font
					(size 1.27 1.27)
					(thickness 0.15)
				)
				(justify left bottom)
				(hide yes)
			)
		)
		(property "Datasheet" ""
			(at 115.57 58.42 0)
			(effects
				(font
					(size 1.27 1.27)
					(thickness 0.15)
				)
				(justify left bottom)
				(hide yes)
			)
		)
		(property "Description" "SMT test point"
			(at 133.35 71.12 0)
			(effects
				(font
					(size 1.27 1.27)
				)
				(hide yes)
			)
		)
		(property "MPN" ""
			(at 122.555 59.69 0)
			(effects
				(font
					(size 1.27 1.27)
					(thickness 0.15)
				)
				(justify left bottom)
				(hide yes)
			)
		)
		(property "Manufacturer" ""
			(at 122.555 64.77 0)
			(effects
				(font
					(size 1.27 1.27)
					(thickness 0.15)
				)
				(justify left bottom)
				(hide yes)
			)
		)
		(property "Author" "Antmicro"
			(at 123.19 62.23 0)
			(effects
				(font
					(size 1.27 1.27)
					(thickness 0.15)
				)
				(justify left bottom)
				(hide yes)
			)
		)
		(property "License" "Apache-2.0"
			(at 123.19 59.69 0)
			(effects
				(font
					(size 1.27 1.27)
					(thickness 0.15)
				)
				(justify left bottom)
				(hide yes)
			)
		)
		(pin "1"
		)
		(instances
			(project "OCuLink to 10GbE adapter"
				(path ""
					(reference "TP6")
					(unit 1)
				)
			)
			(project "thunderbolt-to-10gbe-adapter"
				(path ""
					(reference "TP26")
					(unit 1)
				)
			)
		)
	)
	(symbol
		(lib_id "antmicroLogicTranslatorsLevelShifters:NTS0102_TSSOP")
		(at 130.81 234.95 0)
		(mirror y)
		(unit 1)
		(exclude_from_sim no)
		(in_bom yes)
		(on_board yes)
		(dnp no)
		(fields_autoplaced yes)
		(property "Reference" "U17"
			(at 120.65 227.33 0)
			(effects
				(font
					(size 1.27 1.27)
					(thickness 0.15)
				)
			)
		)
		(property "Value" "NTS0102_TSSOP"
			(at 95.25 241.3 0)
			(effects
				(font
					(size 1.27 1.27)
					(thickness 0.15)
				)
				(justify left bottom)
				(hide yes)
			)
		)
		(property "Footprint" "antmicro-footprints:TSSOP-8_3x3mm_P0.65mm"
			(at 95.25 243.84 0)
			(effects
				(font
					(size 1.27 1.27)
					(thickness 0.15)
				)
				(justify left bottom)
				(hide yes)
			)
		)
		(property "Datasheet" "https://www.mouser.com/datasheet/2/302/NTS0102-1127324.pdf"
			(at 95.25 246.38 0)
			(effects
				(font
					(size 1.27 1.27)
					(thickness 0.15)
				)
				(justify left bottom)
				(hide yes)
			)
		)
		(property "Description" "Transceiver, 1.65 V to 3.6 V, TSSOP-8"
			(at 130.81 234.95 0)
			(effects
				(font
					(size 1.27 1.27)
				)
				(hide yes)
			)
		)
		(property "MPN" "NTS0102DP"
			(at 120.65 229.87 0)
			(effects
				(font
					(size 1.27 1.27)
					(thickness 0.15)
				)
			)
		)
		(property "Manufacturer" "NXP"
			(at 95.25 251.46 0)
			(effects
				(font
					(size 1.27 1.27)
					(thickness 0.15)
				)
				(justify left bottom)
				(hide yes)
			)
		)
		(property "Author" "Antmicro"
			(at 95.25 254 0)
			(effects
				(font
					(size 1.27 1.27)
					(thickness 0.15)
				)
				(justify left bottom)
				(hide yes)
			)
		)
		(property "License" "Apache-2.0"
			(at 95.25 256.54 0)
			(effects
				(font
					(size 1.27 1.27)
					(thickness 0.15)
				)
				(justify left bottom)
				(hide yes)
			)
		)
		(pin "5"
		)
		(pin "3"
		)
		(pin "1"
		)
		(pin "6"
		)
		(pin "7"
		)
		(pin "4"
		)
		(pin "2"
		)
		(pin "8"
		)
		(instances
			(project "OCuLink to 10GbE adapter"
				(path ""
					(reference "U7")
					(unit 1)
				)
			)
			(project "thunderbolt-to-10gbe-adapter"
				(path ""
					(reference "U17")
					(unit 1)
				)
			)
		)
	)
	(symbol
		(lib_id "antmicropower:GND")
		(at 154.94 139.7 0)
		(unit 1)
		(exclude_from_sim no)
		(in_bom yes)
		(on_board yes)
		(dnp no)
		(property "Reference" "#PWR0389"
			(at 163.83 142.24 0)
			(effects
				(font
					(size 1.27 1.27)
					(thickness 0.15)
				)
				(justify left bottom)
				(hide yes)
			)
		)
		(property "Value" "GND"
			(at 154.94 143.51 0)
			(effects
				(font
					(size 1.27 1.27)
					(thickness 0.15)
				)
			)
		)
		(property "Footprint" ""
			(at 163.83 147.32 0)
			(effects
				(font
					(size 1.27 1.27)
					(thickness 0.15)
				)
				(justify left bottom)
				(hide yes)
			)
		)
		(property "Datasheet" ""
			(at 163.83 152.4 0)
			(effects
				(font
					(size 1.27 1.27)
					(thickness 0.15)
				)
				(justify left bottom)
				(hide yes)
			)
		)
		(property "Description" ""
			(at 154.94 139.7 0)
			(effects
				(font
					(size 1.27 1.27)
				)
				(hide yes)
			)
		)
		(property "Author" "Antmicro"
			(at 163.83 147.32 0)
			(effects
				(font
					(size 1.27 1.27)
					(thickness 0.15)
				)
				(justify left bottom)
				(hide yes)
			)
		)
		(property "License" "Apache-2.0"
			(at 163.83 149.86 0)
			(effects
				(font
					(size 1.27 1.27)
					(thickness 0.15)
				)
				(justify left bottom)
				(hide yes)
			)
		)
		(pin "1"
		)
		(instances
			(project "OCuLink to 10GbE adapter"
				(path ""
					(reference "#PWR0269")
					(unit 1)
				)
			)
			(project "thunderbolt-to-10gbe-adapter"
				(path ""
					(reference "#PWR0389")
					(unit 1)
				)
			)
		)
	)
	(symbol
		(lib_id "antmicroResistors0402:R_22R_0402")
		(at 194.31 78.74 0)
		(unit 1)
		(exclude_from_sim no)
		(in_bom yes)
		(on_board yes)
		(dnp no)
		(property "Reference" "R169"
			(at 194.31 77.47 0)
			(effects
				(font
					(size 1.27 1.27)
					(thickness 0.15)
				)
				(justify right)
			)
		)
		(property "Value" "R_22R_0402"
			(at 214.63 91.44 0)
			(effects
				(font
					(size 1.27 1.27)
					(thickness 0.15)
				)
				(justify left bottom)
				(hide yes)
			)
		)
		(property "Footprint" "antmicro-footprints:R_0402_1005Metric"
			(at 214.63 93.98 0)
			(effects
				(font
					(size 1.27 1.27)
					(thickness 0.15)
				)
				(justify left bottom)
				(hide yes)
			)
		)
		(property "Datasheet" "https://www.bourns.com/docs/product-datasheets/cr.pdf"
			(at 214.63 96.52 0)
			(effects
				(font
					(size 1.27 1.27)
					(thickness 0.15)
				)
				(justify left bottom)
				(hide yes)
			)
		)
		(property "Description" "SMD Chip Resistor, 22 ohm, ± 1%, 62.5 mW, 0402 [1005 Metric], Thick Film, General Purpose"
			(at 194.31 78.74 0)
			(effects
				(font
					(size 1.27 1.27)
				)
				(hide yes)
			)
		)
		(property "MPN" "CR0402-FX-22R0GLF"
			(at 214.63 99.06 0)
			(effects
				(font
					(size 1.27 1.27)
					(thickness 0.15)
				)
				(justify left bottom)
				(hide yes)
			)
		)
		(property "Manufacturer" "Bourns"
			(at 214.63 101.6 0)
			(effects
				(font
					(size 1.27 1.27)
					(thickness 0.15)
				)
				(justify left bottom)
				(hide yes)
			)
		)
		(property "License" "Apache-2.0"
			(at 214.63 104.14 0)
			(effects
				(font
					(size 1.27 1.27)
					(thickness 0.15)
				)
				(justify left bottom)
				(hide yes)
			)
		)
		(property "Author" "Antmicro"
			(at 214.63 106.68 0)
			(effects
				(font
					(size 1.27 1.27)
					(thickness 0.15)
				)
				(justify left bottom)
				(hide yes)
			)
		)
		(property "Val" "22R"
			(at 199.39 77.47 0)
			(effects
				(font
					(size 1.27 1.27)
					(thickness 0.15)
				)
				(justify left)
			)
		)
		(property "Tolerance" "1%"
			(at 214.63 88.9 0)
			(effects
				(font
					(size 1.27 1.27)
				)
				(justify left bottom)
				(hide yes)
			)
		)
		(pin "2"
		)
		(pin "1"
		)
		(instances
			(project "OCuLink to 10GbE adapter"
				(path ""
					(reference "R86")
					(unit 1)
				)
			)
			(project "thunderbolt-to-10gbe-adapter"
				(path ""
					(reference "R169")
					(unit 1)
				)
			)
		)
	)
	(symbol
		(lib_id "antmicropower:GND")
		(at 172.72 254 0)
		(unit 1)
		(exclude_from_sim no)
		(in_bom yes)
		(on_board yes)
		(dnp no)
		(property "Reference" "#PWR0396"
			(at 181.61 256.54 0)
			(effects
				(font
					(size 1.27 1.27)
					(thickness 0.15)
				)
				(justify left bottom)
				(hide yes)
			)
		)
		(property "Value" "GND"
			(at 172.72 257.81 0)
			(effects
				(font
					(size 1.27 1.27)
					(thickness 0.15)
				)
			)
		)
		(property "Footprint" ""
			(at 181.61 261.62 0)
			(effects
				(font
					(size 1.27 1.27)
					(thickness 0.15)
				)
				(justify left bottom)
				(hide yes)
			)
		)
		(property "Datasheet" ""
			(at 181.61 266.7 0)
			(effects
				(font
					(size 1.27 1.27)
					(thickness 0.15)
				)
				(justify left bottom)
				(hide yes)
			)
		)
		(property "Description" ""
			(at 172.72 254 0)
			(effects
				(font
					(size 1.27 1.27)
				)
				(hide yes)
			)
		)
		(property "Author" "Antmicro"
			(at 181.61 261.62 0)
			(effects
				(font
					(size 1.27 1.27)
					(thickness 0.15)
				)
				(justify left bottom)
				(hide yes)
			)
		)
		(property "License" "Apache-2.0"
			(at 181.61 264.16 0)
			(effects
				(font
					(size 1.27 1.27)
					(thickness 0.15)
				)
				(justify left bottom)
				(hide yes)
			)
		)
		(pin "1"
		)
		(instances
			(project "OCuLink to 10GbE adapter"
				(path ""
					(reference "#PWR0280")
					(unit 1)
				)
			)
			(project "thunderbolt-to-10gbe-adapter"
				(path ""
					(reference "#PWR0396")
					(unit 1)
				)
			)
		)
	)
	(symbol
		(lib_id "antmicroResistors0402:R_22R_0402")
		(at 194.31 66.04 0)
		(unit 1)
		(exclude_from_sim no)
		(in_bom yes)
		(on_board yes)
		(dnp no)
		(property "Reference" "R167"
			(at 194.31 64.77 0)
			(effects
				(font
					(size 1.27 1.27)
					(thickness 0.15)
				)
				(justify right)
			)
		)
		(property "Value" "R_22R_0402"
			(at 214.63 78.74 0)
			(effects
				(font
					(size 1.27 1.27)
					(thickness 0.15)
				)
				(justify left bottom)
				(hide yes)
			)
		)
		(property "Footprint" "antmicro-footprints:R_0402_1005Metric"
			(at 214.63 81.28 0)
			(effects
				(font
					(size 1.27 1.27)
					(thickness 0.15)
				)
				(justify left bottom)
				(hide yes)
			)
		)
		(property "Datasheet" "https://www.bourns.com/docs/product-datasheets/cr.pdf"
			(at 214.63 83.82 0)
			(effects
				(font
					(size 1.27 1.27)
					(thickness 0.15)
				)
				(justify left bottom)
				(hide yes)
			)
		)
		(property "Description" "SMD Chip Resistor, 22 ohm, ± 1%, 62.5 mW, 0402 [1005 Metric], Thick Film, General Purpose"
			(at 194.31 66.04 0)
			(effects
				(font
					(size 1.27 1.27)
				)
				(hide yes)
			)
		)
		(property "MPN" "CR0402-FX-22R0GLF"
			(at 214.63 86.36 0)
			(effects
				(font
					(size 1.27 1.27)
					(thickness 0.15)
				)
				(justify left bottom)
				(hide yes)
			)
		)
		(property "Manufacturer" "Bourns"
			(at 214.63 88.9 0)
			(effects
				(font
					(size 1.27 1.27)
					(thickness 0.15)
				)
				(justify left bottom)
				(hide yes)
			)
		)
		(property "License" "Apache-2.0"
			(at 214.63 91.44 0)
			(effects
				(font
					(size 1.27 1.27)
					(thickness 0.15)
				)
				(justify left bottom)
				(hide yes)
			)
		)
		(property "Author" "Antmicro"
			(at 214.63 93.98 0)
			(effects
				(font
					(size 1.27 1.27)
					(thickness 0.15)
				)
				(justify left bottom)
				(hide yes)
			)
		)
		(property "Val" "22R"
			(at 199.39 64.77 0)
			(effects
				(font
					(size 1.27 1.27)
					(thickness 0.15)
				)
				(justify left)
			)
		)
		(property "Tolerance" "1%"
			(at 214.63 76.2 0)
			(effects
				(font
					(size 1.27 1.27)
				)
				(justify left bottom)
				(hide yes)
			)
		)
		(pin "2"
		)
		(pin "1"
		)
		(instances
			(project "OCuLink to 10GbE adapter"
				(path ""
					(reference "R84")
					(unit 1)
				)
			)
			(project "thunderbolt-to-10gbe-adapter"
				(path ""
					(reference "R167")
					(unit 1)
				)
			)
		)
	)
	(symbol
		(lib_id "antmicropower:+1V8")
		(at 133.35 218.44 0)
		(mirror y)
		(unit 1)
		(exclude_from_sim no)
		(in_bom yes)
		(on_board yes)
		(dnp no)
		(property "Reference" "#PWR0382"
			(at 118.11 220.98 0)
			(effects
				(font
					(size 1.27 1.27)
					(thickness 0.15)
				)
				(justify left bottom)
				(hide yes)
			)
		)
		(property "Value" "+1V88"
			(at 133.35 214.63 0)
			(effects
				(font
					(size 1.27 1.27)
					(thickness 0.15)
				)
			)
		)
		(property "Footprint" ""
			(at 118.11 226.06 0)
			(effects
				(font
					(size 1.27 1.27)
					(thickness 0.15)
				)
				(justify left bottom)
				(hide yes)
			)
		)
		(property "Datasheet" ""
			(at 118.11 228.6 0)
			(effects
				(font
					(size 1.27 1.27)
					(thickness 0.15)
				)
				(justify left bottom)
				(hide yes)
			)
		)
		(property "Description" ""
			(at 133.35 218.44 0)
			(effects
				(font
					(size 1.27 1.27)
				)
				(hide yes)
			)
		)
		(property "Author" "Antmicro"
			(at 118.11 223.52 0)
			(effects
				(font
					(size 1.27 1.27)
					(thickness 0.15)
				)
				(justify left bottom)
				(hide yes)
			)
		)
		(property "License" "Apache-2.0"
			(at 118.11 226.06 0)
			(effects
				(font
					(size 1.27 1.27)
					(thickness 0.15)
				)
				(justify left bottom)
				(hide yes)
			)
		)
		(pin "1"
		)
		(instances
			(project "OCuLink to 10GbE adapter"
				(path ""
					(reference "#PWR098")
					(unit 1)
				)
			)
			(project "thunderbolt-to-10gbe-adapter"
				(path ""
					(reference "#PWR0382")
					(unit 1)
				)
			)
		)
	)
	(symbol
		(lib_id "antmicropower:GND")
		(at 181.61 254 0)
		(unit 1)
		(exclude_from_sim no)
		(in_bom yes)
		(on_board yes)
		(dnp no)
		(property "Reference" "#PWR0400"
			(at 190.5 256.54 0)
			(effects
				(font
					(size 1.27 1.27)
					(thickness 0.15)
				)
				(justify left bottom)
				(hide yes)
			)
		)
		(property "Value" "GND"
			(at 181.61 257.81 0)
			(effects
				(font
					(size 1.27 1.27)
					(thickness 0.15)
				)
			)
		)
		(property "Footprint" ""
			(at 190.5 261.62 0)
			(effects
				(font
					(size 1.27 1.27)
					(thickness 0.15)
				)
				(justify left bottom)
				(hide yes)
			)
		)
		(property "Datasheet" ""
			(at 190.5 266.7 0)
			(effects
				(font
					(size 1.27 1.27)
					(thickness 0.15)
				)
				(justify left bottom)
				(hide yes)
			)
		)
		(property "Description" ""
			(at 181.61 254 0)
			(effects
				(font
					(size 1.27 1.27)
				)
				(hide yes)
			)
		)
		(property "Author" "Antmicro"
			(at 190.5 261.62 0)
			(effects
				(font
					(size 1.27 1.27)
					(thickness 0.15)
				)
				(justify left bottom)
				(hide yes)
			)
		)
		(property "License" "Apache-2.0"
			(at 190.5 264.16 0)
			(effects
				(font
					(size 1.27 1.27)
					(thickness 0.15)
				)
				(justify left bottom)
				(hide yes)
			)
		)
		(pin "1"
		)
		(instances
			(project "OCuLink to 10GbE adapter"
				(path ""
					(reference "#PWR0281")
					(unit 1)
				)
			)
			(project "thunderbolt-to-10gbe-adapter"
				(path ""
					(reference "#PWR0400")
					(unit 1)
				)
			)
		)
	)
	(symbol
		(lib_id "antmicroResistors0402:R_0R_0402")
		(at 91.44 139.7 0)
		(unit 1)
		(exclude_from_sim no)
		(in_bom yes)
		(on_board yes)
		(dnp yes)
		(property "Reference" "R138"
			(at 91.44 138.43 0)
			(effects
				(font
					(size 1.27 1.27)
					(thickness 0.15)
				)
				(justify right)
			)
		)
		(property "Value" "R_0R_0402"
			(at 111.76 152.4 0)
			(effects
				(font
					(size 1.27 1.27)
					(thickness 0.15)
				)
				(justify left bottom)
				(hide yes)
			)
		)
		(property "Footprint" "antmicro-footprints:R_0402_1005Metric"
			(at 111.76 154.94 0)
			(effects
				(font
					(size 1.27 1.27)
					(thickness 0.15)
				)
				(justify left bottom)
				(hide yes)
			)
		)
		(property "Datasheet" "https://industrial.panasonic.com/cdbs/www-data/pdf/RDA0000/AOA0000C301.pdf"
			(at 111.76 157.48 0)
			(effects
				(font
					(size 1.27 1.27)
					(thickness 0.15)
				)
				(justify left bottom)
				(hide yes)
			)
		)
		(property "Description" "SMD Chip Resistor, Jumper, 0 ohm, 100 mW, 0402 [1005 Metric], Thick Film, General Purpose"
			(at 91.44 139.7 0)
			(effects
				(font
					(size 1.27 1.27)
				)
				(hide yes)
			)
		)
		(property "MPN" "ERJ2GE0R00X"
			(at 111.76 160.02 0)
			(effects
				(font
					(size 1.27 1.27)
					(thickness 0.15)
				)
				(justify left bottom)
				(hide yes)
			)
		)
		(property "Manufacturer" "Panasonic"
			(at 111.76 162.56 0)
			(effects
				(font
					(size 1.27 1.27)
					(thickness 0.15)
				)
				(justify left bottom)
				(hide yes)
			)
		)
		(property "License" "Apache-2.0"
			(at 111.76 165.1 0)
			(effects
				(font
					(size 1.27 1.27)
					(thickness 0.15)
				)
				(justify left bottom)
				(hide yes)
			)
		)
		(property "Author" "Antmicro"
			(at 111.76 167.64 0)
			(effects
				(font
					(size 1.27 1.27)
					(thickness 0.15)
				)
				(justify left bottom)
				(hide yes)
			)
		)
		(property "Val" "0R"
			(at 96.52 138.43 0)
			(effects
				(font
					(size 1.27 1.27)
					(thickness 0.15)
				)
				(justify left)
			)
		)
		(property "Tolerance" "~"
			(at 111.76 149.86 0)
			(effects
				(font
					(size 1.27 1.27)
				)
				(justify left bottom)
				(hide yes)
			)
		)
		(property "Current" "1A"
			(at 111.76 170.18 0)
			(effects
				(font
					(size 1.27 1.27)
					(thickness 0.15)
				)
				(justify left bottom)
				(hide yes)
			)
		)
		(pin "1"
		)
		(pin "2"
		)
		(instances
			(project "thunderbolt-to-10gbe-adapter"
				(path ""
					(reference "R138")
					(unit 1)
				)
			)
		)
	)
	(symbol
		(lib_id "antmicropower:GND")
		(at 105.41 133.35 0)
		(unit 1)
		(exclude_from_sim no)
		(in_bom yes)
		(on_board yes)
		(dnp no)
		(property "Reference" "#PWR0377"
			(at 114.3 135.89 0)
			(effects
				(font
					(size 1.27 1.27)
					(thickness 0.15)
				)
				(justify left bottom)
				(hide yes)
			)
		)
		(property "Value" "GND"
			(at 105.41 137.16 0)
			(effects
				(font
					(size 1.27 1.27)
					(thickness 0.15)
				)
			)
		)
		(property "Footprint" ""
			(at 114.3 140.97 0)
			(effects
				(font
					(size 1.27 1.27)
					(thickness 0.15)
				)
				(justify left bottom)
				(hide yes)
			)
		)
		(property "Datasheet" ""
			(at 114.3 146.05 0)
			(effects
				(font
					(size 1.27 1.27)
					(thickness 0.15)
				)
				(justify left bottom)
				(hide yes)
			)
		)
		(property "Description" ""
			(at 105.41 133.35 0)
			(effects
				(font
					(size 1.27 1.27)
				)
				(hide yes)
			)
		)
		(property "Author" "Antmicro"
			(at 114.3 140.97 0)
			(effects
				(font
					(size 1.27 1.27)
					(thickness 0.15)
				)
				(justify left bottom)
				(hide yes)
			)
		)
		(property "License" "Apache-2.0"
			(at 114.3 143.51 0)
			(effects
				(font
					(size 1.27 1.27)
					(thickness 0.15)
				)
				(justify left bottom)
				(hide yes)
			)
		)
		(pin "1"
		)
		(instances
			(project "OCuLink to 10GbE adapter"
				(path ""
					(reference "#PWR0268")
					(unit 1)
				)
			)
			(project "thunderbolt-to-10gbe-adapter"
				(path ""
					(reference "#PWR0377")
					(unit 1)
				)
			)
		)
	)
	(symbol
		(lib_id "antmicroCapacitors0402:C_100n_0402")
		(at 102.87 228.6 270)
		(mirror x)
		(unit 1)
		(exclude_from_sim no)
		(in_bom yes)
		(on_board yes)
		(dnp no)
		(property "Reference" "C276"
			(at 100.838 224.79 90)
			(effects
				(font
					(size 1.27 1.27)
					(thickness 0.15)
				)
				(justify right)
			)
		)
		(property "Value" "C_100n_0402"
			(at 80.01 213.36 0)
			(effects
				(font
					(size 1.27 1.27)
					(thickness 0.15)
				)
				(justify left bottom)
				(hide yes)
			)
		)
		(property "Footprint" "antmicro-footprints:C_0402_1005Metric"
			(at 77.47 213.36 0)
			(effects
				(font
					(size 1.27 1.27)
					(thickness 0.15)
				)
				(justify left bottom)
				(hide yes)
			)
		)
		(property "Datasheet" "https://www.murata.com/products/productdetail?partno=GRM155R61H104KE14%23"
			(at 74.93 213.36 0)
			(effects
				(font
					(size 1.27 1.27)
					(thickness 0.15)
				)
				(justify left bottom)
				(hide yes)
			)
		)
		(property "Description" "SMD Multilayer Ceramic Capacitor, 0.1 µF, 50 V, 0402 [1005 Metric], ± 10%, X5R, GRM Series"
			(at 102.87 228.6 0)
			(effects
				(font
					(size 1.27 1.27)
				)
				(hide yes)
			)
		)
		(property "MPN" "GRM155R61H104KE14D"
			(at 72.39 213.36 0)
			(effects
				(font
					(size 1.27 1.27)
					(thickness 0.15)
				)
				(justify left bottom)
				(hide yes)
			)
		)
		(property "Val" "100n"
			(at 100.838 227.33 90)
			(effects
				(font
					(size 1.27 1.27)
					(thickness 0.15)
				)
				(justify right)
			)
		)
		(property "Voltage" "50V"
			(at 92.71 213.36 0)
			(effects
				(font
					(size 1.27 1.27)
					(thickness 0.15)
				)
				(justify left bottom)
				(hide yes)
			)
		)
		(property "Dielectric" "X5R"
			(at 90.17 213.36 0)
			(effects
				(font
					(size 1.27 1.27)
					(thickness 0.15)
				)
				(justify left bottom)
				(hide yes)
			)
		)
		(property "Manufacturer" "Murata"
			(at 87.63 213.36 0)
			(effects
				(font
					(size 1.27 1.27)
					(thickness 0.15)
				)
				(justify left bottom)
				(hide yes)
			)
		)
		(property "License" "Apache-2.0"
			(at 85.09 213.36 0)
			(effects
				(font
					(size 1.27 1.27)
					(thickness 0.15)
				)
				(justify left bottom)
				(hide yes)
			)
		)
		(property "Author" "Antmicro"
			(at 82.55 213.36 0)
			(effects
				(font
					(size 1.27 1.27)
					(thickness 0.15)
				)
				(justify left bottom)
				(hide yes)
			)
		)
		(pin "2"
		)
		(pin "1"
		)
		(instances
			(project "OCuLink to 10GbE adapter"
				(path ""
					(reference "C75")
					(unit 1)
				)
			)
			(project "thunderbolt-to-10gbe-adapter"
				(path ""
					(reference "C276")
					(unit 1)
				)
			)
		)
	)
	(symbol
		(lib_id "antmicroResistors0402:R_22R_0402")
		(at 194.31 60.96 0)
		(unit 1)
		(exclude_from_sim no)
		(in_bom yes)
		(on_board yes)
		(dnp no)
		(property "Reference" "R166"
			(at 194.31 59.69 0)
			(effects
				(font
					(size 1.27 1.27)
					(thickness 0.15)
				)
				(justify right)
			)
		)
		(property "Value" "R_22R_0402"
			(at 214.63 73.66 0)
			(effects
				(font
					(size 1.27 1.27)
					(thickness 0.15)
				)
				(justify left bottom)
				(hide yes)
			)
		)
		(property "Footprint" "antmicro-footprints:R_0402_1005Metric"
			(at 214.63 76.2 0)
			(effects
				(font
					(size 1.27 1.27)
					(thickness 0.15)
				)
				(justify left bottom)
				(hide yes)
			)
		)
		(property "Datasheet" "https://www.bourns.com/docs/product-datasheets/cr.pdf"
			(at 214.63 78.74 0)
			(effects
				(font
					(size 1.27 1.27)
					(thickness 0.15)
				)
				(justify left bottom)
				(hide yes)
			)
		)
		(property "Description" "SMD Chip Resistor, 22 ohm, ± 1%, 62.5 mW, 0402 [1005 Metric], Thick Film, General Purpose"
			(at 194.31 60.96 0)
			(effects
				(font
					(size 1.27 1.27)
				)
				(hide yes)
			)
		)
		(property "MPN" "CR0402-FX-22R0GLF"
			(at 214.63 81.28 0)
			(effects
				(font
					(size 1.27 1.27)
					(thickness 0.15)
				)
				(justify left bottom)
				(hide yes)
			)
		)
		(property "Manufacturer" "Bourns"
			(at 214.63 83.82 0)
			(effects
				(font
					(size 1.27 1.27)
					(thickness 0.15)
				)
				(justify left bottom)
				(hide yes)
			)
		)
		(property "License" "Apache-2.0"
			(at 214.63 86.36 0)
			(effects
				(font
					(size 1.27 1.27)
					(thickness 0.15)
				)
				(justify left bottom)
				(hide yes)
			)
		)
		(property "Author" "Antmicro"
			(at 214.63 88.9 0)
			(effects
				(font
					(size 1.27 1.27)
					(thickness 0.15)
				)
				(justify left bottom)
				(hide yes)
			)
		)
		(property "Val" "22R"
			(at 199.39 59.69 0)
			(effects
				(font
					(size 1.27 1.27)
					(thickness 0.15)
				)
				(justify left)
			)
		)
		(property "Tolerance" "1%"
			(at 214.63 71.12 0)
			(effects
				(font
					(size 1.27 1.27)
				)
				(justify left bottom)
				(hide yes)
			)
		)
		(pin "2"
		)
		(pin "1"
		)
		(instances
			(project ""
				(path ""
					(reference "R83")
					(unit 1)
				)
			)
			(project "thunderbolt-to-10gbe-adapter"
				(path ""
					(reference "R166")
					(unit 1)
				)
			)
		)
	)
	(symbol
		(lib_id "antmicroTestPoints:TP_0.75mm_SMD")
		(at 210.82 236.22 180)
		(unit 1)
		(exclude_from_sim no)
		(in_bom no)
		(on_board yes)
		(dnp no)
		(property "Reference" "TP32"
			(at 206.502 236.22 0)
			(effects
				(font
					(size 1.27 1.27)
					(thickness 0.15)
				)
				(justify left)
			)
		)
		(property "Value" "TP_0.75mm_SMD"
			(at 200.66 232.41 0)
			(effects
				(font
					(size 1.27 1.27)
					(thickness 0.15)
				)
				(justify left bottom)
				(hide yes)
			)
		)
		(property "Footprint" "antmicro-footprints:TP_SMD_0.75mm"
			(at 200.66 229.87 0)
			(effects
				(font
					(size 1.27 1.27)
					(thickness 0.15)
				)
				(justify left bottom)
				(hide yes)
			)
		)
		(property "Datasheet" ""
			(at 193.04 223.52 0)
			(effects
				(font
					(size 1.27 1.27)
					(thickness 0.15)
				)
				(justify left bottom)
				(hide yes)
			)
		)
		(property "Description" "SMT test point"
			(at 210.82 236.22 0)
			(effects
				(font
					(size 1.27 1.27)
				)
				(hide yes)
			)
		)
		(property "MPN" ""
			(at 200.025 224.79 0)
			(effects
				(font
					(size 1.27 1.27)
					(thickness 0.15)
				)
				(justify left bottom)
				(hide yes)
			)
		)
		(property "Manufacturer" ""
			(at 200.025 229.87 0)
			(effects
				(font
					(size 1.27 1.27)
					(thickness 0.15)
				)
				(justify left bottom)
				(hide yes)
			)
		)
		(property "Author" "Antmicro"
			(at 200.66 227.33 0)
			(effects
				(font
					(size 1.27 1.27)
					(thickness 0.15)
				)
				(justify left bottom)
				(hide yes)
			)
		)
		(property "License" "Apache-2.0"
			(at 200.66 224.79 0)
			(effects
				(font
					(size 1.27 1.27)
					(thickness 0.15)
				)
				(justify left bottom)
				(hide yes)
			)
		)
		(pin "1"
		)
		(instances
			(project "OCuLink to 10GbE adapter"
				(path ""
					(reference "TP11")
					(unit 1)
				)
			)
			(project "thunderbolt-to-10gbe-adapter"
				(path ""
					(reference "TP32")
					(unit 1)
				)
			)
		)
	)
	(symbol
		(lib_id "antmicropower:+3V3")
		(at 107.95 176.53 0)
		(mirror y)
		(unit 1)
		(exclude_from_sim no)
		(in_bom yes)
		(on_board yes)
		(dnp no)
		(property "Reference" "#PWR0378"
			(at 92.71 176.53 0)
			(effects
				(font
					(size 1.27 1.27)
					(thickness 0.15)
				)
				(justify left bottom)
				(hide yes)
			)
		)
		(property "Value" "+3V3"
			(at 107.95 172.72 0)
			(effects
				(font
					(size 1.27 1.27)
					(thickness 0.15)
				)
			)
		)
		(property "Footprint" ""
			(at 92.71 184.15 0)
			(effects
				(font
					(size 1.27 1.27)
					(thickness 0.15)
				)
				(justify left bottom)
				(hide yes)
			)
		)
		(property "Datasheet" ""
			(at 92.71 186.69 0)
			(effects
				(font
					(size 1.27 1.27)
					(thickness 0.15)
				)
				(justify left bottom)
				(hide yes)
			)
		)
		(property "Description" ""
			(at 107.95 176.53 0)
			(effects
				(font
					(size 1.27 1.27)
				)
				(hide yes)
			)
		)
		(property "Author" "Antmicro"
			(at 92.71 179.07 0)
			(effects
				(font
					(size 1.27 1.27)
					(thickness 0.15)
				)
				(justify left bottom)
				(hide yes)
			)
		)
		(property "License" "Apache-2.0"
			(at 92.71 181.61 0)
			(effects
				(font
					(size 1.27 1.27)
					(thickness 0.15)
				)
				(justify left bottom)
				(hide yes)
			)
		)
		(pin "1"
		)
		(instances
			(project "OCuLink to 10GbE adapter"
				(path ""
					(reference "#PWR0108")
					(unit 1)
				)
			)
			(project "thunderbolt-to-10gbe-adapter"
				(path ""
					(reference "#PWR0378")
					(unit 1)
				)
			)
		)
	)
	(symbol
		(lib_id "antmicroResistors0402:R_1k_0402")
		(at 285.75 165.1 90)
		(unit 1)
		(exclude_from_sim no)
		(in_bom yes)
		(on_board yes)
		(dnp no)
		(property "Reference" "R176"
			(at 287.274 161.29 90)
			(effects
				(font
					(size 1.27 1.27)
					(thickness 0.15)
				)
				(justify right)
			)
		)
		(property "Value" "R_1k_0402"
			(at 298.45 144.78 0)
			(effects
				(font
					(size 1.27 1.27)
					(thickness 0.15)
				)
				(justify left bottom)
				(hide yes)
			)
		)
		(property "Footprint" "antmicro-footprints:R_0402_1005Metric"
			(at 300.99 144.78 0)
			(effects
				(font
					(size 1.27 1.27)
					(thickness 0.15)
				)
				(justify left bottom)
				(hide yes)
			)
		)
		(property "Datasheet" "https://www.bourns.com/docs/product-datasheets/cr.pdf"
			(at 303.53 144.78 0)
			(effects
				(font
					(size 1.27 1.27)
					(thickness 0.15)
				)
				(justify left bottom)
				(hide yes)
			)
		)
		(property "Description" "SMD Chip Resistor, 1 kohm, ± 1%, 63 mW, 0402 [1005 Metric], Thick Film, General Purpose"
			(at 285.75 165.1 0)
			(effects
				(font
					(size 1.27 1.27)
				)
				(hide yes)
			)
		)
		(property "MPN" "CR0402-FX-1001GLF"
			(at 306.07 144.78 0)
			(effects
				(font
					(size 1.27 1.27)
					(thickness 0.15)
				)
				(justify left bottom)
				(hide yes)
			)
		)
		(property "Manufacturer" "Bourns"
			(at 308.61 144.78 0)
			(effects
				(font
					(size 1.27 1.27)
					(thickness 0.15)
				)
				(justify left bottom)
				(hide yes)
			)
		)
		(property "License" "Apache-2.0"
			(at 311.15 144.78 0)
			(effects
				(font
					(size 1.27 1.27)
					(thickness 0.15)
				)
				(justify left bottom)
				(hide yes)
			)
		)
		(property "Author" "Antmicro"
			(at 313.69 144.78 0)
			(effects
				(font
					(size 1.27 1.27)
					(thickness 0.15)
				)
				(justify left bottom)
				(hide yes)
			)
		)
		(property "Val" "1k"
			(at 287.274 163.83 90)
			(effects
				(font
					(size 1.27 1.27)
					(thickness 0.15)
				)
				(justify right)
			)
		)
		(property "Tolerance" "1%"
			(at 295.91 144.78 0)
			(effects
				(font
					(size 1.27 1.27)
				)
				(justify left bottom)
				(hide yes)
			)
		)
		(pin "2"
		)
		(pin "1"
		)
		(instances
			(project "OCuLink to 10GbE adapter"
				(path ""
					(reference "R112")
					(unit 1)
				)
			)
			(project "thunderbolt-to-10gbe-adapter"
				(path ""
					(reference "R176")
					(unit 1)
				)
			)
		)
	)
	(symbol
		(lib_id "antmicropower:GND")
		(at 73.66 121.92 0)
		(unit 1)
		(exclude_from_sim no)
		(in_bom yes)
		(on_board yes)
		(dnp no)
		(property "Reference" "#PWR0373"
			(at 82.55 124.46 0)
			(effects
				(font
					(size 1.27 1.27)
					(thickness 0.15)
				)
				(justify left bottom)
				(hide yes)
			)
		)
		(property "Value" "GND"
			(at 73.66 125.73 0)
			(effects
				(font
					(size 1.27 1.27)
					(thickness 0.15)
				)
			)
		)
		(property "Footprint" ""
			(at 82.55 129.54 0)
			(effects
				(font
					(size 1.27 1.27)
					(thickness 0.15)
				)
				(justify left bottom)
				(hide yes)
			)
		)
		(property "Datasheet" ""
			(at 82.55 134.62 0)
			(effects
				(font
					(size 1.27 1.27)
					(thickness 0.15)
				)
				(justify left bottom)
				(hide yes)
			)
		)
		(property "Description" ""
			(at 73.66 121.92 0)
			(effects
				(font
					(size 1.27 1.27)
				)
				(hide yes)
			)
		)
		(property "Author" "Antmicro"
			(at 82.55 129.54 0)
			(effects
				(font
					(size 1.27 1.27)
					(thickness 0.15)
				)
				(justify left bottom)
				(hide yes)
			)
		)
		(property "License" "Apache-2.0"
			(at 82.55 132.08 0)
			(effects
				(font
					(size 1.27 1.27)
					(thickness 0.15)
				)
				(justify left bottom)
				(hide yes)
			)
		)
		(pin "1"
		)
		(instances
			(project "OCuLink to 10GbE adapter"
				(path ""
					(reference "#PWR0267")
					(unit 1)
				)
			)
			(project "thunderbolt-to-10gbe-adapter"
				(path ""
					(reference "#PWR0373")
					(unit 1)
				)
			)
		)
	)
	(symbol
		(lib_id "antmicroResistors0402:R_2k_0402")
		(at 200.66 193.04 270)
		(mirror x)
		(unit 1)
		(exclude_from_sim no)
		(in_bom yes)
		(on_board yes)
		(dnp no)
		(property "Reference" "R172"
			(at 199.136 189.23 90)
			(effects
				(font
					(size 1.27 1.27)
					(thickness 0.15)
				)
				(justify right)
			)
		)
		(property "Value" "R_2k_0402"
			(at 187.96 172.72 0)
			(effects
				(font
					(size 1.27 1.27)
					(thickness 0.15)
				)
				(justify left bottom)
				(hide yes)
			)
		)
		(property "Footprint" "antmicro-footprints:R_0402_1005Metric"
			(at 185.42 172.72 0)
			(effects
				(font
					(size 1.27 1.27)
					(thickness 0.15)
				)
				(justify left bottom)
				(hide yes)
			)
		)
		(property "Datasheet" "https://www.bourns.com/docs/product-datasheets/cr.pdf"
			(at 182.88 172.72 0)
			(effects
				(font
					(size 1.27 1.27)
					(thickness 0.15)
				)
				(justify left bottom)
				(hide yes)
			)
		)
		(property "Description" "SMD Chip Resistor, 2 kohm, ± 1%, 62.5 mW, 0402 [1005 Metric], Thick Film, General Purpose"
			(at 200.66 193.04 0)
			(effects
				(font
					(size 1.27 1.27)
				)
				(hide yes)
			)
		)
		(property "MPN" "CR0402-FX-2001GLF"
			(at 180.34 172.72 0)
			(effects
				(font
					(size 1.27 1.27)
					(thickness 0.15)
				)
				(justify left bottom)
				(hide yes)
			)
		)
		(property "Manufacturer" "Bourns"
			(at 177.8 172.72 0)
			(effects
				(font
					(size 1.27 1.27)
					(thickness 0.15)
				)
				(justify left bottom)
				(hide yes)
			)
		)
		(property "License" "Apache-2.0"
			(at 175.26 172.72 0)
			(effects
				(font
					(size 1.27 1.27)
					(thickness 0.15)
				)
				(justify left bottom)
				(hide yes)
			)
		)
		(property "Author" "Antmicro"
			(at 172.72 172.72 0)
			(effects
				(font
					(size 1.27 1.27)
					(thickness 0.15)
				)
				(justify left bottom)
				(hide yes)
			)
		)
		(property "Val" "2k"
			(at 199.136 191.77 90)
			(effects
				(font
					(size 1.27 1.27)
					(thickness 0.15)
				)
				(justify right)
			)
		)
		(property "Tolerance" "1%"
			(at 190.5 172.72 0)
			(effects
				(font
					(size 1.27 1.27)
				)
				(justify left bottom)
				(hide yes)
			)
		)
		(pin "1"
		)
		(pin "2"
		)
		(instances
			(project "OCuLink to 10GbE adapter"
				(path ""
					(reference "R114")
					(unit 1)
				)
			)
			(project "thunderbolt-to-10gbe-adapter"
				(path ""
					(reference "R172")
					(unit 1)
				)
			)
		)
	)
	(symbol
		(lib_id "antmicroResistors0402:R_100R_0402")
		(at 139.7 240.03 0)
		(unit 1)
		(exclude_from_sim no)
		(in_bom yes)
		(on_board yes)
		(dnp no)
		(property "Reference" "R141"
			(at 139.7 238.76 0)
			(effects
				(font
					(size 1.27 1.27)
					(thickness 0.15)
				)
				(justify right)
			)
		)
		(property "Value" "R_100R_0402"
			(at 160.02 252.73 0)
			(effects
				(font
					(size 1.27 1.27)
					(thickness 0.15)
				)
				(justify left bottom)
				(hide yes)
			)
		)
		(property "Footprint" "antmicro-footprints:R_0402_1005Metric"
			(at 160.02 255.27 0)
			(effects
				(font
					(size 1.27 1.27)
					(thickness 0.15)
				)
				(justify left bottom)
				(hide yes)
			)
		)
		(property "Datasheet" "https://www.bourns.com/docs/product-datasheets/cr.pdf"
			(at 160.02 257.81 0)
			(effects
				(font
					(size 1.27 1.27)
					(thickness 0.15)
				)
				(justify left bottom)
				(hide yes)
			)
		)
		(property "Description" "SMD Chip Resistor, 100 ohm, ± 1%, 62.5 mW, 0402 [1005 Metric], Thick Film, General Purpose"
			(at 160.02 270.51 0)
			(effects
				(font
					(size 1.27 1.27)
				)
				(justify left bottom)
				(hide yes)
			)
		)
		(property "MPN" "CR0402-FX-1000GLF"
			(at 160.02 260.35 0)
			(effects
				(font
					(size 1.27 1.27)
					(thickness 0.15)
				)
				(justify left bottom)
				(hide yes)
			)
		)
		(property "Manufacturer" "Bourns"
			(at 160.02 262.89 0)
			(effects
				(font
					(size 1.27 1.27)
					(thickness 0.15)
				)
				(justify left bottom)
				(hide yes)
			)
		)
		(property "License" "Apache-2.0"
			(at 160.02 265.43 0)
			(effects
				(font
					(size 1.27 1.27)
					(thickness 0.15)
				)
				(justify left bottom)
				(hide yes)
			)
		)
		(property "Author" "Antmicro"
			(at 160.02 267.97 0)
			(effects
				(font
					(size 1.27 1.27)
					(thickness 0.15)
				)
				(justify left bottom)
				(hide yes)
			)
		)
		(property "Val" "100R"
			(at 144.78 238.76 0)
			(effects
				(font
					(size 1.27 1.27)
					(thickness 0.15)
				)
				(justify left)
			)
		)
		(property "Tolerance" "1%"
			(at 160.02 250.19 0)
			(effects
				(font
					(size 1.27 1.27)
				)
				(justify left bottom)
				(hide yes)
			)
		)
		(pin "2"
		)
		(pin "1"
		)
		(instances
			(project "OCuLink to 10GbE adapter"
				(path ""
					(reference "R49")
					(unit 1)
				)
			)
			(project "thunderbolt-to-10gbe-adapter"
				(path ""
					(reference "R141")
					(unit 1)
				)
			)
		)
	)
	(symbol
		(lib_id "antmicropower:GND")
		(at 160.02 182.88 0)
		(unit 1)
		(exclude_from_sim no)
		(in_bom yes)
		(on_board yes)
		(dnp no)
		(property "Reference" "#PWR0390"
			(at 168.91 185.42 0)
			(effects
				(font
					(size 1.27 1.27)
					(thickness 0.15)
				)
				(justify left bottom)
				(hide yes)
			)
		)
		(property "Value" "GND"
			(at 160.02 186.69 0)
			(effects
				(font
					(size 1.27 1.27)
					(thickness 0.15)
				)
			)
		)
		(property "Footprint" ""
			(at 168.91 190.5 0)
			(effects
				(font
					(size 1.27 1.27)
					(thickness 0.15)
				)
				(justify left bottom)
				(hide yes)
			)
		)
		(property "Datasheet" ""
			(at 168.91 195.58 0)
			(effects
				(font
					(size 1.27 1.27)
					(thickness 0.15)
				)
				(justify left bottom)
				(hide yes)
			)
		)
		(property "Description" ""
			(at 160.02 182.88 0)
			(effects
				(font
					(size 1.27 1.27)
				)
				(hide yes)
			)
		)
		(property "Author" "Antmicro"
			(at 168.91 190.5 0)
			(effects
				(font
					(size 1.27 1.27)
					(thickness 0.15)
				)
				(justify left bottom)
				(hide yes)
			)
		)
		(property "License" "Apache-2.0"
			(at 168.91 193.04 0)
			(effects
				(font
					(size 1.27 1.27)
					(thickness 0.15)
				)
				(justify left bottom)
				(hide yes)
			)
		)
		(pin "1"
		)
		(instances
			(project "OCuLink to 10GbE adapter"
				(path ""
					(reference "#PWR095")
					(unit 1)
				)
			)
			(project "thunderbolt-to-10gbe-adapter"
				(path ""
					(reference "#PWR0390")
					(unit 1)
				)
			)
		)
	)
	(symbol
		(lib_id "antmicroInterfaceControllers:EZX710AT2_S_LMR5")
		(at 228.6 81.28 0)
		(unit 4)
		(exclude_from_sim no)
		(in_bom yes)
		(on_board yes)
		(dnp no)
		(fields_autoplaced yes)
		(property "Reference" "U14"
			(at 255.27 73.66 0)
			(effects
				(font
					(size 1.27 1.27)
					(thickness 0.15)
				)
			)
		)
		(property "Value" "EZX710AT2_S_LMR5"
			(at 304.8 86.36 0)
			(effects
				(font
					(size 1.27 1.27)
					(thickness 0.15)
				)
				(justify left bottom)
				(hide yes)
			)
		)
		(property "Footprint" "antmicro-footprints:FCBGA-503_22x22mm_Layout21x24_P1mm"
			(at 304.8 88.9 0)
			(effects
				(font
					(size 1.27 1.27)
					(thickness 0.15)
				)
				(justify left bottom)
				(hide yes)
			)
		)
		(property "Datasheet" "https://www.google.com/url?sa=t&source=web&rct=j&opi=89978449&url=https://cdrdv2-public.intel.com/596333/596333_X710-TM4_Datasheet_v_2_4.pdf&ved=2ahUKEwiSuv20_sCOAxXVCRAIHdxGO_UQFnoECBEQAQ&usg=AOvVaw1CjGyrGWE8ZvOdw4VBsY6U"
			(at 304.8 91.44 0)
			(effects
				(font
					(size 1.27 1.27)
					(thickness 0.15)
				)
				(justify left bottom)
				(hide yes)
			)
		)
		(property "Description" "Ethernet ICs Intel Ethernet Controller 10 Gigabit X7"
			(at 304.8 93.98 0)
			(effects
				(font
					(size 1.27 1.27)
					(thickness 0.15)
				)
				(justify left bottom)
				(hide yes)
			)
		)
		(property "MPN" "EZX710AT2 S LMR5"
			(at 255.27 76.2 0)
			(effects
				(font
					(size 1.27 1.27)
					(thickness 0.15)
				)
			)
		)
		(property "Manufacturer" "Intel"
			(at 304.8 96.52 0)
			(effects
				(font
					(size 1.27 1.27)
					(thickness 0.15)
				)
				(justify left bottom)
				(hide yes)
			)
		)
		(property "Author" "Antmicro"
			(at 304.8 99.06 0)
			(effects
				(font
					(size 1.27 1.27)
					(thickness 0.15)
				)
				(justify left bottom)
				(hide yes)
			)
		)
		(property "License" "Apache-2.0"
			(at 304.8 101.6 0)
			(effects
				(font
					(size 1.27 1.27)
					(thickness 0.15)
				)
				(justify left bottom)
				(hide yes)
			)
		)
		(pin "B26"
		)
		(pin "E7"
		)
		(pin "G9"
		)
		(pin "E5"
		)
		(pin "A17"
		)
		(pin "J15"
		)
		(pin "P34"
		)
		(pin "AD30"
		)
		(pin "J7"
		)
		(pin "C1"
		)
		(pin "G37"
		)
		(pin "N37"
		)
		(pin "F38"
		)
		(pin "B2"
		)
		(pin "N29"
		)
		(pin "D4"
		)
		(pin "Y24"
		)
		(pin "N35"
		)
		(pin "C5"
		)
		(pin "V42"
		)
		(pin "M20"
		)
		(pin "P10"
		)
		(pin "L37"
		)
		(pin "B34"
		)
		(pin "U37"
		)
		(pin "AC7"
		)
		(pin "M4"
		)
		(pin "U35"
		)
		(pin "D18"
		)
		(pin "H16"
		)
		(pin "V30"
		)
		(pin "B38"
		)
		(pin "W29"
		)
		(pin "AB22"
		)
		(pin "AC15"
		)
		(pin "B28"
		)
		(pin "G3"
		)
		(pin "P32"
		)
		(pin "H14"
		)
		(pin "G13"
		)
		(pin "B30"
		)
		(pin "D22"
		)
		(pin "V10"
		)
		(pin "B24"
		)
		(pin "AD4"
		)
		(pin "AC5"
		)
		(pin "AA5"
		)
		(pin "V24"
		)
		(pin "V6"
		)
		(pin "D10"
		)
		(pin "AD20"
		)
		(pin "T26"
		)
		(pin "T10"
		)
		(pin "T12"
		)
		(pin "AD6"
		)
		(pin "H8"
		)
		(pin "H28"
		)
		(pin "N15"
		)
		(pin "AC29"
		)
		(pin "N17"
		)
		(pin "W31"
		)
		(pin "Y12"
		)
		(pin "W23"
		)
		(pin "AD32"
		)
		(pin "AB16"
		)
		(pin "T28"
		)
		(pin "D24"
		)
		(pin "D26"
		)
		(pin "G17"
		)
		(pin "K32"
		)
		(pin "F24"
		)
		(pin "F26"
		)
		(pin "J31"
		)
		(pin "T30"
		)
		(pin "AD34"
		)
		(pin "AA27"
		)
		(pin "R17"
		)
		(pin "W13"
		)
		(pin "M26"
		)
		(pin "C9"
		)
		(pin "AA41"
		)
		(pin "AC27"
		)
		(pin "K2"
		)
		(pin "AB20"
		)
		(pin "R7"
		)
		(pin "N39"
		)
		(pin "D6"
		)
		(pin "M22"
		)
		(pin "M2"
		)
		(pin "AC9"
		)
		(pin "A3"
		)
		(pin "P2"
		)
		(pin "AA33"
		)
		(pin "A23"
		)
		(pin "E35"
		)
		(pin "U3"
		)
		(pin "V36"
		)
		(pin "K42"
		)
		(pin "R41"
		)
		(pin "R1"
		)
		(pin "AD22"
		)
		(pin "W7"
		)
		(pin "AB18"
		)
		(pin "E19"
		)
		(pin "AB12"
		)
		(pin "AD28"
		)
		(pin "AD40"
		)
		(pin "J1"
		)
		(pin "Y6"
		)
		(pin "Y8"
		)
		(pin "H36"
		)
		(pin "C13"
		)
		(pin "C23"
		)
		(pin "Y38"
		)
		(pin "U21"
		)
		(pin "F32"
		)
		(pin "F34"
		)
		(pin "A25"
		)
		(pin "N23"
		)
		(pin "W41"
		)
		(pin "AC31"
		)
		(pin "D12"
		)
		(pin "K34"
		)
		(pin "AA23"
		)
		(pin "AC17"
		)
		(pin "V22"
		)
		(pin "AA39"
		)
		(pin "J41"
		)
		(pin "V14"
		)
		(pin "U23"
		)
		(pin "V16"
		)
		(pin "W35"
		)
		(pin "AC21"
		)
		(pin "D32"
		)
		(pin "L1"
		)
		(pin "P24"
		)
		(pin "J3"
		)
		(pin "AC41"
		)
		(pin "AD14"
		)
		(pin "K22"
		)
		(pin "A11"
		)
		(pin "AA15"
		)
		(pin "F2"
		)
		(pin "A9"
		)
		(pin "N27"
		)
		(pin "C19"
		)
		(pin "K30"
		)
		(pin "L23"
		)
		(pin "N41"
		)
		(pin "F20"
		)
		(pin "AB28"
		)
		(pin "AD12"
		)
		(pin "C21"
		)
		(pin "U9"
		)
		(pin "V20"
		)
		(pin "D20"
		)
		(pin "L21"
		)
		(pin "R15"
		)
		(pin "K4"
		)
		(pin "N1"
		)
		(pin "H12"
		)
		(pin "J23"
		)
		(pin "J5"
		)
		(pin "E9"
		)
		(pin "M28"
		)
		(pin "U1"
		)
		(pin "Y2"
		)
		(pin "G5"
		)
		(pin "K20"
		)
		(pin "M18"
		)
		(pin "V2"
		)
		(pin "AC39"
		)
		(pin "T32"
		)
		(pin "E25"
		)
		(pin "AD38"
		)
		(pin "H26"
		)
		(pin "AA31"
		)
		(pin "G31"
		)
		(pin "U27"
		)
		(pin "U17"
		)
		(pin "C11"
		)
		(pin "N3"
		)
		(pin "A37"
		)
		(pin "F6"
		)
		(pin "Y30"
		)
		(pin "U7"
		)
		(pin "G15"
		)
		(pin "C29"
		)
		(pin "E39"
		)
		(pin "A35"
		)
		(pin "L3"
		)
		(pin "N25"
		)
		(pin "R25"
		)
		(pin "J37"
		)
		(pin "H42"
		)
		(pin "AD24"
		)
		(pin "B14"
		)
		(pin "P6"
		)
		(pin "R31"
		)
		(pin "A5"
		)
		(pin "D14"
		)
		(pin "AB10"
		)
		(pin "B18"
		)
		(pin "A27"
		)
		(pin "T40"
		)
		(pin "AB40"
		)
		(pin "P4"
		)
		(pin "AA35"
		)
		(pin "F36"
		)
		(pin "K18"
		)
		(pin "K38"
		)
		(pin "N33"
		)
		(pin "Y26"
		)
		(pin "Y28"
		)
		(pin "G21"
		)
		(pin "AA1"
		)
		(pin "AB2"
		)
		(pin "V38"
		)
		(pin "J9"
		)
		(pin "B6"
		)
		(pin "L35"
		)
		(pin "N7"
		)
		(pin "AC1"
		)
		(pin "E23"
		)
		(pin "F40"
		)
		(pin "F42"
		)
		(pin "P36"
		)
		(pin "F4"
		)
		(pin "AD16"
		)
		(pin "R11"
		)
		(pin "R27"
		)
		(pin "J13"
		)
		(pin "V34"
		)
		(pin "M10"
		)
		(pin "Y4"
		)
		(pin "Y40"
		)
		(pin "L27"
		)
		(pin "L9"
		)
		(pin "K10"
		)
		(pin "L39"
		)
		(pin "U5"
		)
		(pin "AB42"
		)
		(pin "R5"
		)
		(pin "G23"
		)
		(pin "M8"
		)
		(pin "AD8"
		)
		(pin "M16"
		)
		(pin "M12"
		)
		(pin "E3"
		)
		(pin "B12"
		)
		(pin "R23"
		)
		(pin "W25"
		)
		(pin "H4"
		)
		(pin "F8"
		)
		(pin "AC23"
		)
		(pin "AA3"
		)
		(pin "B10"
		)
		(pin "E31"
		)
		(pin "E33"
		)
		(pin "G1"
		)
		(pin "F18"
		)
		(pin "W17"
		)
		(pin "K36"
		)
		(pin "AB26"
		)
		(pin "R13"
		)
		(pin "AB32"
		)
		(pin "V18"
		)
		(pin "D16"
		)
		(pin "AA37"
		)
		(pin "C31"
		)
		(pin "C41"
		)
		(pin "A41"
		)
		(pin "E1"
		)
		(pin "P38"
		)
		(pin "U19"
		)
		(pin "R29"
		)
		(pin "E37"
		)
		(pin "E29"
		)
		(pin "A21"
		)
		(pin "A31"
		)
		(pin "U29"
		)
		(pin "AB34"
		)
		(pin "E17"
		)
		(pin "W15"
		)
		(pin "H40"
		)
		(pin "M24"
		)
		(pin "U15"
		)
		(pin "H2"
		)
		(pin "N21"
		)
		(pin "W33"
		)
		(pin "J29"
		)
		(pin "T42"
		)
		(pin "A13"
		)
		(pin "AD26"
		)
		(pin "P28"
		)
		(pin "T24"
		)
		(pin "F12"
		)
		(pin "AD2"
		)
		(pin "H34"
		)
		(pin "J33"
		)
		(pin "P40"
		)
		(pin "C17"
		)
		(pin "W19"
		)
		(pin "M6"
		)
		(pin "H6"
		)
		(pin "M40"
		)
		(pin "D30"
		)
		(pin "F10"
		)
		(pin "Y14"
		)
		(pin "L29"
		)
		(pin "P22"
		)
		(pin "W1"
		)
		(pin "V28"
		)
		(pin "E11"
		)
		(pin "J25"
		)
		(pin "G27"
		)
		(pin "M34"
		)
		(pin "Y18"
		)
		(pin "K8"
		)
		(pin "AC35"
		)
		(pin "AD36"
		)
		(pin "G19"
		)
		(pin "G41"
		)
		(pin "W3"
		)
		(pin "C37"
		)
		(pin "C27"
		)
		(pin "Y22"
		)
		(pin "C35"
		)
		(pin "L41"
		)
		(pin "P30"
		)
		(pin "V8"
		)
		(pin "AB30"
		)
		(pin "A29"
		)
		(pin "B22"
		)
		(pin "B32"
		)
		(pin "T36"
		)
		(pin "AA17"
		)
		(pin "K12"
		)
		(pin "P8"
		)
		(pin "T22"
		)
		(pin "C15"
		)
		(pin "W9"
		)
		(pin "W11"
		)
		(pin "P42"
		)
		(pin "T6"
		)
		(pin "B40"
		)
		(pin "N9"
		)
		(pin "K6"
		)
		(pin "A33"
		)
		(pin "T38"
		)
		(pin "J35"
		)
		(pin "E41"
		)
		(pin "T2"
		)
		(pin "C3"
		)
		(pin "R3"
		)
		(pin "D8"
		)
		(pin "F28"
		)
		(pin "F30"
		)
		(pin "Y32"
		)
		(pin "Y36"
		)
		(pin "AC25"
		)
		(pin "T4"
		)
		(pin "V26"
		)
		(pin "B16"
		)
		(pin "V32"
		)
		(pin "H10"
		)
		(pin "A7"
		)
		(pin "R9"
		)
		(pin "N11"
		)
		(pin "R37"
		)
		(pin "W37"
		)
		(pin "V4"
		)
		(pin "T14"
		)
		(pin "T16"
		)
		(pin "J21"
		)
		(pin "AB14"
		)
		(pin "J17"
		)
		(pin "W5"
		)
		(pin "D34"
		)
		(pin "Y34"
		)
		(pin "M36"
		)
		(pin "AA25"
		)
		(pin "B4"
		)
		(pin "AA29"
		)
		(pin "K16"
		)
		(pin "V40"
		)
		(pin "AC37"
		)
		(pin "AB24"
		)
		(pin "AD18"
		)
		(pin "AA7"
		)
		(pin "V12"
		)
		(pin "AC13"
		)
		(pin "T8"
		)
		(pin "E21"
		)
		(pin "A19"
		)
		(pin "E27"
		)
		(pin "K14"
		)
		(pin "AA13"
		)
		(pin "P16"
		)
		(pin "P18"
		)
		(pin "H30"
		)
		(pin "N31"
		)
		(pin "P12"
		)
		(pin "P14"
		)
		(pin "B42"
		)
		(pin "G25"
		)
		(pin "U25"
		)
		(pin "A39"
		)
		(pin "J11"
		)
		(pin "G11"
		)
		(pin "G29"
		)
		(pin "R19"
		)
		(pin "AC11"
		)
		(pin "F22"
		)
		(pin "W39"
		)
		(pin "AA9"
		)
		(pin "AB38"
		)
		(pin "L31"
		)
		(pin "T34"
		)
		(pin "J39"
		)
		(pin "F14"
		)
		(pin "H24"
		)
		(pin "G35"
		)
		(pin "W21"
		)
		(pin "K40"
		)
		(pin "N19"
		)
		(pin "B20"
		)
		(pin "U31"
		)
		(pin "R21"
		)
		(pin "R39"
		)
		(pin "P20"
		)
		(pin "R35"
		)
		(pin "AD42"
		)
		(pin "K24"
		)
		(pin "AB4"
		)
		(pin "AC33"
		)
		(pin "B8"
		)
		(pin "U33"
		)
		(pin "H32"
		)
		(pin "L33"
		)
		(pin "J19"
		)
		(pin "U13"
		)
		(pin "C39"
		)
		(pin "H22"
		)
		(pin "AD10"
		)
		(pin "Y20"
		)
		(pin "E15"
		)
		(pin "AA21"
		)
		(pin "K26"
		)
		(pin "C25"
		)
		(pin "M42"
		)
		(pin "U41"
		)
		(pin "Y16"
		)
		(pin "D28"
		)
		(pin "D36"
		)
		(pin "Y10"
		)
		(pin "AC19"
		)
		(pin "AB8"
		)
		(pin "AB36"
		)
		(pin "P26"
		)
		(pin "D38"
		)
		(pin "D40"
		)
		(pin "AA19"
		)
		(pin "E13"
		)
		(pin "A15"
		)
		(pin "H20"
		)
		(pin "K28"
		)
		(pin "F16"
		)
		(pin "W27"
		)
		(pin "D42"
		)
		(pin "AB6"
		)
		(pin "M14"
		)
		(pin "M32"
		)
		(pin "N5"
		)
		(pin "U11"
		)
		(pin "J27"
		)
		(pin "M30"
		)
		(pin "C33"
		)
		(pin "C7"
		)
		(pin "L15"
		)
		(pin "G33"
		)
		(pin "L19"
		)
		(pin "L17"
		)
		(pin "L5"
		)
		(pin "L25"
		)
		(pin "M38"
		)
		(pin "T18"
		)
		(pin "T20"
		)
		(pin "H18"
		)
		(pin "G7"
		)
		(pin "B36"
		)
		(pin "U39"
		)
		(pin "G39"
		)
		(pin "D2"
		)
		(pin "R33"
		)
		(pin "L11"
		)
		(pin "AC3"
		)
		(pin "AA11"
		)
		(pin "H38"
		)
		(pin "N13"
		)
		(pin "L13"
		)
		(pin "L7"
		)
		(pin "Y42"
		)
		(instances
			(project "OCuLink to 10GbE adapter"
				(path ""
					(reference "U9")
					(unit 4)
				)
			)
			(project "thunderbolt-to-10gbe-adapter"
				(path ""
					(reference "U14")
					(unit 4)
				)
			)
		)
	)
	(symbol
		(lib_id "antmicroInterfaceControllers:EZX710AT2_S_LMR5")
		(at 223.52 167.64 0)
		(unit 6)
		(exclude_from_sim no)
		(in_bom yes)
		(on_board yes)
		(dnp no)
		(fields_autoplaced yes)
		(property "Reference" "U14"
			(at 251.46 160.02 0)
			(effects
				(font
					(size 1.27 1.27)
					(thickness 0.15)
				)
			)
		)
		(property "Value" "EZX710AT2_S_LMR5"
			(at 299.72 172.72 0)
			(effects
				(font
					(size 1.27 1.27)
					(thickness 0.15)
				)
				(justify left bottom)
				(hide yes)
			)
		)
		(property "Footprint" "antmicro-footprints:FCBGA-503_22x22mm_Layout21x24_P1mm"
			(at 299.72 175.26 0)
			(effects
				(font
					(size 1.27 1.27)
					(thickness 0.15)
				)
				(justify left bottom)
				(hide yes)
			)
		)
		(property "Datasheet" "https://www.google.com/url?sa=t&source=web&rct=j&opi=89978449&url=https://cdrdv2-public.intel.com/596333/596333_X710-TM4_Datasheet_v_2_4.pdf&ved=2ahUKEwiSuv20_sCOAxXVCRAIHdxGO_UQFnoECBEQAQ&usg=AOvVaw1CjGyrGWE8ZvOdw4VBsY6U"
			(at 299.72 177.8 0)
			(effects
				(font
					(size 1.27 1.27)
					(thickness 0.15)
				)
				(justify left bottom)
				(hide yes)
			)
		)
		(property "Description" "Ethernet ICs Intel Ethernet Controller 10 Gigabit X7"
			(at 299.72 180.34 0)
			(effects
				(font
					(size 1.27 1.27)
					(thickness 0.15)
				)
				(justify left bottom)
				(hide yes)
			)
		)
		(property "MPN" "EZX710AT2 S LMR5"
			(at 251.46 162.56 0)
			(effects
				(font
					(size 1.27 1.27)
					(thickness 0.15)
				)
			)
		)
		(property "Manufacturer" "Intel"
			(at 299.72 182.88 0)
			(effects
				(font
					(size 1.27 1.27)
					(thickness 0.15)
				)
				(justify left bottom)
				(hide yes)
			)
		)
		(property "Author" "Antmicro"
			(at 299.72 185.42 0)
			(effects
				(font
					(size 1.27 1.27)
					(thickness 0.15)
				)
				(justify left bottom)
				(hide yes)
			)
		)
		(property "License" "Apache-2.0"
			(at 299.72 187.96 0)
			(effects
				(font
					(size 1.27 1.27)
					(thickness 0.15)
				)
				(justify left bottom)
				(hide yes)
			)
		)
		(pin "B26"
		)
		(pin "E7"
		)
		(pin "G9"
		)
		(pin "E5"
		)
		(pin "A17"
		)
		(pin "J15"
		)
		(pin "P34"
		)
		(pin "AD30"
		)
		(pin "J7"
		)
		(pin "C1"
		)
		(pin "G37"
		)
		(pin "N37"
		)
		(pin "F38"
		)
		(pin "B2"
		)
		(pin "N29"
		)
		(pin "D4"
		)
		(pin "Y24"
		)
		(pin "N35"
		)
		(pin "C5"
		)
		(pin "V42"
		)
		(pin "M20"
		)
		(pin "P10"
		)
		(pin "L37"
		)
		(pin "B34"
		)
		(pin "U37"
		)
		(pin "AC7"
		)
		(pin "M4"
		)
		(pin "U35"
		)
		(pin "D18"
		)
		(pin "H16"
		)
		(pin "V30"
		)
		(pin "B38"
		)
		(pin "W29"
		)
		(pin "AB22"
		)
		(pin "AC15"
		)
		(pin "B28"
		)
		(pin "G3"
		)
		(pin "P32"
		)
		(pin "H14"
		)
		(pin "G13"
		)
		(pin "B30"
		)
		(pin "D22"
		)
		(pin "V10"
		)
		(pin "B24"
		)
		(pin "AD4"
		)
		(pin "AC5"
		)
		(pin "AA5"
		)
		(pin "V24"
		)
		(pin "V6"
		)
		(pin "D10"
		)
		(pin "AD20"
		)
		(pin "T26"
		)
		(pin "T10"
		)
		(pin "T12"
		)
		(pin "AD6"
		)
		(pin "H8"
		)
		(pin "H28"
		)
		(pin "N15"
		)
		(pin "AC29"
		)
		(pin "N17"
		)
		(pin "W31"
		)
		(pin "Y12"
		)
		(pin "W23"
		)
		(pin "AD32"
		)
		(pin "AB16"
		)
		(pin "T28"
		)
		(pin "D24"
		)
		(pin "D26"
		)
		(pin "G17"
		)
		(pin "K32"
		)
		(pin "F24"
		)
		(pin "F26"
		)
		(pin "J31"
		)
		(pin "T30"
		)
		(pin "AD34"
		)
		(pin "AA27"
		)
		(pin "R17"
		)
		(pin "W13"
		)
		(pin "M26"
		)
		(pin "C9"
		)
		(pin "AA41"
		)
		(pin "AC27"
		)
		(pin "K2"
		)
		(pin "AB20"
		)
		(pin "R7"
		)
		(pin "N39"
		)
		(pin "D6"
		)
		(pin "M22"
		)
		(pin "M2"
		)
		(pin "AC9"
		)
		(pin "A3"
		)
		(pin "P2"
		)
		(pin "AA33"
		)
		(pin "A23"
		)
		(pin "E35"
		)
		(pin "U3"
		)
		(pin "V36"
		)
		(pin "K42"
		)
		(pin "R41"
		)
		(pin "R1"
		)
		(pin "AD22"
		)
		(pin "W7"
		)
		(pin "AB18"
		)
		(pin "E19"
		)
		(pin "AB12"
		)
		(pin "AD28"
		)
		(pin "AD40"
		)
		(pin "J1"
		)
		(pin "Y6"
		)
		(pin "Y8"
		)
		(pin "H36"
		)
		(pin "C13"
		)
		(pin "C23"
		)
		(pin "Y38"
		)
		(pin "U21"
		)
		(pin "F32"
		)
		(pin "F34"
		)
		(pin "A25"
		)
		(pin "N23"
		)
		(pin "W41"
		)
		(pin "AC31"
		)
		(pin "D12"
		)
		(pin "K34"
		)
		(pin "AA23"
		)
		(pin "AC17"
		)
		(pin "V22"
		)
		(pin "AA39"
		)
		(pin "J41"
		)
		(pin "V14"
		)
		(pin "U23"
		)
		(pin "V16"
		)
		(pin "W35"
		)
		(pin "AC21"
		)
		(pin "D32"
		)
		(pin "L1"
		)
		(pin "P24"
		)
		(pin "J3"
		)
		(pin "AC41"
		)
		(pin "AD14"
		)
		(pin "K22"
		)
		(pin "A11"
		)
		(pin "AA15"
		)
		(pin "F2"
		)
		(pin "A9"
		)
		(pin "N27"
		)
		(pin "C19"
		)
		(pin "K30"
		)
		(pin "L23"
		)
		(pin "N41"
		)
		(pin "F20"
		)
		(pin "AB28"
		)
		(pin "AD12"
		)
		(pin "C21"
		)
		(pin "U9"
		)
		(pin "V20"
		)
		(pin "D20"
		)
		(pin "L21"
		)
		(pin "R15"
		)
		(pin "K4"
		)
		(pin "N1"
		)
		(pin "H12"
		)
		(pin "J23"
		)
		(pin "J5"
		)
		(pin "E9"
		)
		(pin "M28"
		)
		(pin "U1"
		)
		(pin "Y2"
		)
		(pin "G5"
		)
		(pin "K20"
		)
		(pin "M18"
		)
		(pin "V2"
		)
		(pin "AC39"
		)
		(pin "T32"
		)
		(pin "E25"
		)
		(pin "AD38"
		)
		(pin "H26"
		)
		(pin "AA31"
		)
		(pin "G31"
		)
		(pin "U27"
		)
		(pin "U17"
		)
		(pin "C11"
		)
		(pin "N3"
		)
		(pin "A37"
		)
		(pin "F6"
		)
		(pin "Y30"
		)
		(pin "U7"
		)
		(pin "G15"
		)
		(pin "C29"
		)
		(pin "E39"
		)
		(pin "A35"
		)
		(pin "L3"
		)
		(pin "N25"
		)
		(pin "R25"
		)
		(pin "J37"
		)
		(pin "H42"
		)
		(pin "AD24"
		)
		(pin "B14"
		)
		(pin "P6"
		)
		(pin "R31"
		)
		(pin "A5"
		)
		(pin "D14"
		)
		(pin "AB10"
		)
		(pin "B18"
		)
		(pin "A27"
		)
		(pin "T40"
		)
		(pin "AB40"
		)
		(pin "P4"
		)
		(pin "AA35"
		)
		(pin "F36"
		)
		(pin "K18"
		)
		(pin "K38"
		)
		(pin "N33"
		)
		(pin "Y26"
		)
		(pin "Y28"
		)
		(pin "G21"
		)
		(pin "AA1"
		)
		(pin "AB2"
		)
		(pin "V38"
		)
		(pin "J9"
		)
		(pin "B6"
		)
		(pin "L35"
		)
		(pin "N7"
		)
		(pin "AC1"
		)
		(pin "E23"
		)
		(pin "F40"
		)
		(pin "F42"
		)
		(pin "P36"
		)
		(pin "F4"
		)
		(pin "AD16"
		)
		(pin "R11"
		)
		(pin "R27"
		)
		(pin "J13"
		)
		(pin "V34"
		)
		(pin "M10"
		)
		(pin "Y4"
		)
		(pin "Y40"
		)
		(pin "L27"
		)
		(pin "L9"
		)
		(pin "K10"
		)
		(pin "L39"
		)
		(pin "U5"
		)
		(pin "AB42"
		)
		(pin "R5"
		)
		(pin "G23"
		)
		(pin "M8"
		)
		(pin "AD8"
		)
		(pin "M16"
		)
		(pin "M12"
		)
		(pin "E3"
		)
		(pin "B12"
		)
		(pin "R23"
		)
		(pin "W25"
		)
		(pin "H4"
		)
		(pin "F8"
		)
		(pin "AC23"
		)
		(pin "AA3"
		)
		(pin "B10"
		)
		(pin "E31"
		)
		(pin "E33"
		)
		(pin "G1"
		)
		(pin "F18"
		)
		(pin "W17"
		)
		(pin "K36"
		)
		(pin "AB26"
		)
		(pin "R13"
		)
		(pin "AB32"
		)
		(pin "V18"
		)
		(pin "D16"
		)
		(pin "AA37"
		)
		(pin "C31"
		)
		(pin "C41"
		)
		(pin "A41"
		)
		(pin "E1"
		)
		(pin "P38"
		)
		(pin "U19"
		)
		(pin "R29"
		)
		(pin "E37"
		)
		(pin "E29"
		)
		(pin "A21"
		)
		(pin "A31"
		)
		(pin "U29"
		)
		(pin "AB34"
		)
		(pin "E17"
		)
		(pin "W15"
		)
		(pin "H40"
		)
		(pin "M24"
		)
		(pin "U15"
		)
		(pin "H2"
		)
		(pin "N21"
		)
		(pin "W33"
		)
		(pin "J29"
		)
		(pin "T42"
		)
		(pin "A13"
		)
		(pin "AD26"
		)
		(pin "P28"
		)
		(pin "T24"
		)
		(pin "F12"
		)
		(pin "AD2"
		)
		(pin "H34"
		)
		(pin "J33"
		)
		(pin "P40"
		)
		(pin "C17"
		)
		(pin "W19"
		)
		(pin "M6"
		)
		(pin "H6"
		)
		(pin "M40"
		)
		(pin "D30"
		)
		(pin "F10"
		)
		(pin "Y14"
		)
		(pin "L29"
		)
		(pin "P22"
		)
		(pin "W1"
		)
		(pin "V28"
		)
		(pin "E11"
		)
		(pin "J25"
		)
		(pin "G27"
		)
		(pin "M34"
		)
		(pin "Y18"
		)
		(pin "K8"
		)
		(pin "AC35"
		)
		(pin "AD36"
		)
		(pin "G19"
		)
		(pin "G41"
		)
		(pin "W3"
		)
		(pin "C37"
		)
		(pin "C27"
		)
		(pin "Y22"
		)
		(pin "C35"
		)
		(pin "L41"
		)
		(pin "P30"
		)
		(pin "V8"
		)
		(pin "AB30"
		)
		(pin "A29"
		)
		(pin "B22"
		)
		(pin "B32"
		)
		(pin "T36"
		)
		(pin "AA17"
		)
		(pin "K12"
		)
		(pin "P8"
		)
		(pin "T22"
		)
		(pin "C15"
		)
		(pin "W9"
		)
		(pin "W11"
		)
		(pin "P42"
		)
		(pin "T6"
		)
		(pin "B40"
		)
		(pin "N9"
		)
		(pin "K6"
		)
		(pin "A33"
		)
		(pin "T38"
		)
		(pin "J35"
		)
		(pin "E41"
		)
		(pin "T2"
		)
		(pin "C3"
		)
		(pin "R3"
		)
		(pin "D8"
		)
		(pin "F28"
		)
		(pin "F30"
		)
		(pin "Y32"
		)
		(pin "Y36"
		)
		(pin "AC25"
		)
		(pin "T4"
		)
		(pin "V26"
		)
		(pin "B16"
		)
		(pin "V32"
		)
		(pin "H10"
		)
		(pin "A7"
		)
		(pin "R9"
		)
		(pin "N11"
		)
		(pin "R37"
		)
		(pin "W37"
		)
		(pin "V4"
		)
		(pin "T14"
		)
		(pin "T16"
		)
		(pin "J21"
		)
		(pin "AB14"
		)
		(pin "J17"
		)
		(pin "W5"
		)
		(pin "D34"
		)
		(pin "Y34"
		)
		(pin "M36"
		)
		(pin "AA25"
		)
		(pin "B4"
		)
		(pin "AA29"
		)
		(pin "K16"
		)
		(pin "V40"
		)
		(pin "AC37"
		)
		(pin "AB24"
		)
		(pin "AD18"
		)
		(pin "AA7"
		)
		(pin "V12"
		)
		(pin "AC13"
		)
		(pin "T8"
		)
		(pin "E21"
		)
		(pin "A19"
		)
		(pin "E27"
		)
		(pin "K14"
		)
		(pin "AA13"
		)
		(pin "P16"
		)
		(pin "P18"
		)
		(pin "H30"
		)
		(pin "N31"
		)
		(pin "P12"
		)
		(pin "P14"
		)
		(pin "B42"
		)
		(pin "G25"
		)
		(pin "U25"
		)
		(pin "A39"
		)
		(pin "J11"
		)
		(pin "G11"
		)
		(pin "G29"
		)
		(pin "R19"
		)
		(pin "AC11"
		)
		(pin "F22"
		)
		(pin "W39"
		)
		(pin "AA9"
		)
		(pin "AB38"
		)
		(pin "L31"
		)
		(pin "T34"
		)
		(pin "J39"
		)
		(pin "F14"
		)
		(pin "H24"
		)
		(pin "G35"
		)
		(pin "W21"
		)
		(pin "K40"
		)
		(pin "N19"
		)
		(pin "B20"
		)
		(pin "U31"
		)
		(pin "R21"
		)
		(pin "R39"
		)
		(pin "P20"
		)
		(pin "R35"
		)
		(pin "AD42"
		)
		(pin "K24"
		)
		(pin "AB4"
		)
		(pin "AC33"
		)
		(pin "B8"
		)
		(pin "U33"
		)
		(pin "H32"
		)
		(pin "L33"
		)
		(pin "J19"
		)
		(pin "U13"
		)
		(pin "C39"
		)
		(pin "H22"
		)
		(pin "AD10"
		)
		(pin "Y20"
		)
		(pin "E15"
		)
		(pin "AA21"
		)
		(pin "K26"
		)
		(pin "C25"
		)
		(pin "M42"
		)
		(pin "U41"
		)
		(pin "Y16"
		)
		(pin "D28"
		)
		(pin "D36"
		)
		(pin "Y10"
		)
		(pin "AC19"
		)
		(pin "AB8"
		)
		(pin "AB36"
		)
		(pin "P26"
		)
		(pin "D38"
		)
		(pin "D40"
		)
		(pin "AA19"
		)
		(pin "E13"
		)
		(pin "A15"
		)
		(pin "H20"
		)
		(pin "K28"
		)
		(pin "F16"
		)
		(pin "W27"
		)
		(pin "D42"
		)
		(pin "AB6"
		)
		(pin "M14"
		)
		(pin "M32"
		)
		(pin "N5"
		)
		(pin "U11"
		)
		(pin "J27"
		)
		(pin "M30"
		)
		(pin "C33"
		)
		(pin "C7"
		)
		(pin "L15"
		)
		(pin "G33"
		)
		(pin "L19"
		)
		(pin "L17"
		)
		(pin "L5"
		)
		(pin "L25"
		)
		(pin "M38"
		)
		(pin "T18"
		)
		(pin "T20"
		)
		(pin "H18"
		)
		(pin "G7"
		)
		(pin "B36"
		)
		(pin "U39"
		)
		(pin "G39"
		)
		(pin "D2"
		)
		(pin "R33"
		)
		(pin "L11"
		)
		(pin "AC3"
		)
		(pin "AA11"
		)
		(pin "H38"
		)
		(pin "N13"
		)
		(pin "L13"
		)
		(pin "L7"
		)
		(pin "Y42"
		)
		(instances
			(project "OCuLink to 10GbE adapter"
				(path ""
					(reference "U9")
					(unit 6)
				)
			)
			(project "thunderbolt-to-10gbe-adapter"
				(path ""
					(reference "U14")
					(unit 6)
				)
			)
		)
	)
	(symbol
		(lib_id "antmicroTestPoints:TP_0.75mm_SMD")
		(at 133.35 60.96 180)
		(unit 1)
		(exclude_from_sim no)
		(in_bom no)
		(on_board yes)
		(dnp no)
		(property "Reference" "TP22"
			(at 129.032 60.96 0)
			(effects
				(font
					(size 1.27 1.27)
					(thickness 0.15)
				)
				(justify left)
			)
		)
		(property "Value" "TP_0.75mm_SMD"
			(at 123.19 57.15 0)
			(effects
				(font
					(size 1.27 1.27)
					(thickness 0.15)
				)
				(justify left bottom)
				(hide yes)
			)
		)
		(property "Footprint" "antmicro-footprints:TP_SMD_0.75mm"
			(at 123.19 54.61 0)
			(effects
				(font
					(size 1.27 1.27)
					(thickness 0.15)
				)
				(justify left bottom)
				(hide yes)
			)
		)
		(property "Datasheet" ""
			(at 115.57 48.26 0)
			(effects
				(font
					(size 1.27 1.27)
					(thickness 0.15)
				)
				(justify left bottom)
				(hide yes)
			)
		)
		(property "Description" "SMT test point"
			(at 133.35 60.96 0)
			(effects
				(font
					(size 1.27 1.27)
				)
				(hide yes)
			)
		)
		(property "MPN" ""
			(at 122.555 49.53 0)
			(effects
				(font
					(size 1.27 1.27)
					(thickness 0.15)
				)
				(justify left bottom)
				(hide yes)
			)
		)
		(property "Manufacturer" ""
			(at 122.555 54.61 0)
			(effects
				(font
					(size 1.27 1.27)
					(thickness 0.15)
				)
				(justify left bottom)
				(hide yes)
			)
		)
		(property "Author" "Antmicro"
			(at 123.19 52.07 0)
			(effects
				(font
					(size 1.27 1.27)
					(thickness 0.15)
				)
				(justify left bottom)
				(hide yes)
			)
		)
		(property "License" "Apache-2.0"
			(at 123.19 49.53 0)
			(effects
				(font
					(size 1.27 1.27)
					(thickness 0.15)
				)
				(justify left bottom)
				(hide yes)
			)
		)
		(pin "1"
		)
		(instances
			(project "OCuLink to 10GbE adapter"
				(path ""
					(reference "TP2")
					(unit 1)
				)
			)
			(project "thunderbolt-to-10gbe-adapter"
				(path ""
					(reference "TP22")
					(unit 1)
				)
			)
		)
	)
	(symbol
		(lib_id "antmicroCapacitors0402:C_100n_0402")
		(at 137.16 228.6 90)
		(unit 1)
		(exclude_from_sim no)
		(in_bom yes)
		(on_board yes)
		(dnp no)
		(property "Reference" "C277"
			(at 139.192 224.79 90)
			(effects
				(font
					(size 1.27 1.27)
					(thickness 0.15)
				)
				(justify right)
			)
		)
		(property "Value" "C_100n_0402"
			(at 160.02 213.36 0)
			(effects
				(font
					(size 1.27 1.27)
					(thickness 0.15)
				)
				(justify left bottom)
				(hide yes)
			)
		)
		(property "Footprint" "antmicro-footprints:C_0402_1005Metric"
			(at 162.56 213.36 0)
			(effects
				(font
					(size 1.27 1.27)
					(thickness 0.15)
				)
				(justify left bottom)
				(hide yes)
			)
		)
		(property "Datasheet" "https://www.murata.com/products/productdetail?partno=GRM155R61H104KE14%23"
			(at 165.1 213.36 0)
			(effects
				(font
					(size 1.27 1.27)
					(thickness 0.15)
				)
				(justify left bottom)
				(hide yes)
			)
		)
		(property "Description" "SMD Multilayer Ceramic Capacitor, 0.1 µF, 50 V, 0402 [1005 Metric], ± 10%, X5R, GRM Series"
			(at 137.16 228.6 0)
			(effects
				(font
					(size 1.27 1.27)
				)
				(hide yes)
			)
		)
		(property "MPN" "GRM155R61H104KE14D"
			(at 167.64 213.36 0)
			(effects
				(font
					(size 1.27 1.27)
					(thickness 0.15)
				)
				(justify left bottom)
				(hide yes)
			)
		)
		(property "Val" "100n"
			(at 139.192 227.33 90)
			(effects
				(font
					(size 1.27 1.27)
					(thickness 0.15)
				)
				(justify right)
			)
		)
		(property "Voltage" "50V"
			(at 147.32 213.36 0)
			(effects
				(font
					(size 1.27 1.27)
					(thickness 0.15)
				)
				(justify left bottom)
				(hide yes)
			)
		)
		(property "Dielectric" "X5R"
			(at 149.86 213.36 0)
			(effects
				(font
					(size 1.27 1.27)
					(thickness 0.15)
				)
				(justify left bottom)
				(hide yes)
			)
		)
		(property "Manufacturer" "Murata"
			(at 152.4 213.36 0)
			(effects
				(font
					(size 1.27 1.27)
					(thickness 0.15)
				)
				(justify left bottom)
				(hide yes)
			)
		)
		(property "License" "Apache-2.0"
			(at 154.94 213.36 0)
			(effects
				(font
					(size 1.27 1.27)
					(thickness 0.15)
				)
				(justify left bottom)
				(hide yes)
			)
		)
		(property "Author" "Antmicro"
			(at 157.48 213.36 0)
			(effects
				(font
					(size 1.27 1.27)
					(thickness 0.15)
				)
				(justify left bottom)
				(hide yes)
			)
		)
		(pin "2"
		)
		(pin "1"
		)
		(instances
			(project "OCuLink to 10GbE adapter"
				(path ""
					(reference "C74")
					(unit 1)
				)
			)
			(project "thunderbolt-to-10gbe-adapter"
				(path ""
					(reference "C277")
					(unit 1)
				)
			)
		)
	)
	(symbol
		(lib_id "antmicroResistors0402:R_10k_0402")
		(at 167.64 111.76 90)
		(unit 1)
		(exclude_from_sim no)
		(in_bom yes)
		(on_board yes)
		(dnp yes)
		(property "Reference" "R150"
			(at 168.91 107.95 90)
			(effects
				(font
					(size 1.27 1.27)
					(thickness 0.15)
				)
				(justify right)
			)
		)
		(property "Value" "R_10k_0402"
			(at 180.34 91.44 0)
			(effects
				(font
					(size 1.27 1.27)
					(thickness 0.15)
				)
				(justify left bottom)
				(hide yes)
			)
		)
		(property "Footprint" "antmicro-footprints:R_0402_1005Metric"
			(at 182.88 91.44 0)
			(effects
				(font
					(size 1.27 1.27)
					(thickness 0.15)
				)
				(justify left bottom)
				(hide yes)
			)
		)
		(property "Datasheet" "https://www.bourns.com/docs/product-datasheets/cr.pdf"
			(at 185.42 91.44 0)
			(effects
				(font
					(size 1.27 1.27)
					(thickness 0.15)
				)
				(justify left bottom)
				(hide yes)
			)
		)
		(property "Description" "SMD Chip Resistor, 10 kohm, ± 1%, 62.5 mW, 0402 [1005 Metric], Thick Film, General Purpose"
			(at 167.64 111.76 0)
			(effects
				(font
					(size 1.27 1.27)
				)
				(hide yes)
			)
		)
		(property "MPN" "CR0402-FX-1002GLF"
			(at 187.96 91.44 0)
			(effects
				(font
					(size 1.27 1.27)
					(thickness 0.15)
				)
				(justify left bottom)
				(hide yes)
			)
		)
		(property "Manufacturer" "Bourns"
			(at 190.5 91.44 0)
			(effects
				(font
					(size 1.27 1.27)
					(thickness 0.15)
				)
				(justify left bottom)
				(hide yes)
			)
		)
		(property "License" "Apache-2.0"
			(at 193.04 91.44 0)
			(effects
				(font
					(size 1.27 1.27)
					(thickness 0.15)
				)
				(justify left bottom)
				(hide yes)
			)
		)
		(property "Author" "Antmicro"
			(at 195.58 91.44 0)
			(effects
				(font
					(size 1.27 1.27)
					(thickness 0.15)
				)
				(justify left bottom)
				(hide yes)
			)
		)
		(property "Val" "10k"
			(at 168.91 110.49 90)
			(effects
				(font
					(size 1.27 1.27)
					(thickness 0.15)
				)
				(justify right)
			)
		)
		(property "Tolerance" "1%"
			(at 177.8 91.44 0)
			(effects
				(font
					(size 1.27 1.27)
				)
				(justify left bottom)
				(hide yes)
			)
		)
		(pin "2"
		)
		(pin "1"
		)
		(instances
			(project "OCuLink to 10GbE adapter"
				(path ""
					(reference "R97")
					(unit 1)
				)
			)
			(project "thunderbolt-to-10gbe-adapter"
				(path ""
					(reference "R150")
					(unit 1)
				)
			)
		)
	)
	(symbol
		(lib_id "antmicroResistors0402:R_10k_0402")
		(at 288.29 104.14 90)
		(unit 1)
		(exclude_from_sim no)
		(in_bom yes)
		(on_board yes)
		(dnp no)
		(property "Reference" "R177"
			(at 289.814 100.33 90)
			(effects
				(font
					(size 1.27 1.27)
					(thickness 0.15)
				)
				(justify right)
			)
		)
		(property "Value" "R_10k_0402"
			(at 300.99 83.82 0)
			(effects
				(font
					(size 1.27 1.27)
					(thickness 0.15)
				)
				(justify left bottom)
				(hide yes)
			)
		)
		(property "Footprint" "antmicro-footprints:R_0402_1005Metric"
			(at 303.53 83.82 0)
			(effects
				(font
					(size 1.27 1.27)
					(thickness 0.15)
				)
				(justify left bottom)
				(hide yes)
			)
		)
		(property "Datasheet" "https://www.bourns.com/docs/product-datasheets/cr.pdf"
			(at 306.07 83.82 0)
			(effects
				(font
					(size 1.27 1.27)
					(thickness 0.15)
				)
				(justify left bottom)
				(hide yes)
			)
		)
		(property "Description" "SMD Chip Resistor, 10 kohm, ± 1%, 62.5 mW, 0402 [1005 Metric], Thick Film, General Purpose"
			(at 288.29 104.14 0)
			(effects
				(font
					(size 1.27 1.27)
				)
				(hide yes)
			)
		)
		(property "MPN" "CR0402-FX-1002GLF"
			(at 308.61 83.82 0)
			(effects
				(font
					(size 1.27 1.27)
					(thickness 0.15)
				)
				(justify left bottom)
				(hide yes)
			)
		)
		(property "Manufacturer" "Bourns"
			(at 311.15 83.82 0)
			(effects
				(font
					(size 1.27 1.27)
					(thickness 0.15)
				)
				(justify left bottom)
				(hide yes)
			)
		)
		(property "License" "Apache-2.0"
			(at 313.69 83.82 0)
			(effects
				(font
					(size 1.27 1.27)
					(thickness 0.15)
				)
				(justify left bottom)
				(hide yes)
			)
		)
		(property "Author" "Antmicro"
			(at 316.23 83.82 0)
			(effects
				(font
					(size 1.27 1.27)
					(thickness 0.15)
				)
				(justify left bottom)
				(hide yes)
			)
		)
		(property "Val" "10k"
			(at 289.814 102.87 90)
			(effects
				(font
					(size 1.27 1.27)
					(thickness 0.15)
				)
				(justify right)
			)
		)
		(property "Tolerance" "1%"
			(at 298.45 83.82 0)
			(effects
				(font
					(size 1.27 1.27)
				)
				(justify left bottom)
				(hide yes)
			)
		)
		(pin "2"
		)
		(pin "1"
		)
		(instances
			(project "OCuLink to 10GbE adapter"
				(path ""
					(reference "R91")
					(unit 1)
				)
			)
			(project "thunderbolt-to-10gbe-adapter"
				(path ""
					(reference "R177")
					(unit 1)
				)
			)
		)
	)
	(symbol
		(lib_id "antmicroResistors0402:R_22R_0402")
		(at 194.31 73.66 0)
		(unit 1)
		(exclude_from_sim no)
		(in_bom yes)
		(on_board yes)
		(dnp no)
		(property "Reference" "R168"
			(at 194.31 72.39 0)
			(effects
				(font
					(size 1.27 1.27)
					(thickness 0.15)
				)
				(justify right)
			)
		)
		(property "Value" "R_22R_0402"
			(at 214.63 86.36 0)
			(effects
				(font
					(size 1.27 1.27)
					(thickness 0.15)
				)
				(justify left bottom)
				(hide yes)
			)
		)
		(property "Footprint" "antmicro-footprints:R_0402_1005Metric"
			(at 214.63 88.9 0)
			(effects
				(font
					(size 1.27 1.27)
					(thickness 0.15)
				)
				(justify left bottom)
				(hide yes)
			)
		)
		(property "Datasheet" "https://www.bourns.com/docs/product-datasheets/cr.pdf"
			(at 214.63 91.44 0)
			(effects
				(font
					(size 1.27 1.27)
					(thickness 0.15)
				)
				(justify left bottom)
				(hide yes)
			)
		)
		(property "Description" "SMD Chip Resistor, 22 ohm, ± 1%, 62.5 mW, 0402 [1005 Metric], Thick Film, General Purpose"
			(at 194.31 73.66 0)
			(effects
				(font
					(size 1.27 1.27)
				)
				(hide yes)
			)
		)
		(property "MPN" "CR0402-FX-22R0GLF"
			(at 214.63 93.98 0)
			(effects
				(font
					(size 1.27 1.27)
					(thickness 0.15)
				)
				(justify left bottom)
				(hide yes)
			)
		)
		(property "Manufacturer" "Bourns"
			(at 214.63 96.52 0)
			(effects
				(font
					(size 1.27 1.27)
					(thickness 0.15)
				)
				(justify left bottom)
				(hide yes)
			)
		)
		(property "License" "Apache-2.0"
			(at 214.63 99.06 0)
			(effects
				(font
					(size 1.27 1.27)
					(thickness 0.15)
				)
				(justify left bottom)
				(hide yes)
			)
		)
		(property "Author" "Antmicro"
			(at 214.63 101.6 0)
			(effects
				(font
					(size 1.27 1.27)
					(thickness 0.15)
				)
				(justify left bottom)
				(hide yes)
			)
		)
		(property "Val" "22R"
			(at 199.39 72.39 0)
			(effects
				(font
					(size 1.27 1.27)
					(thickness 0.15)
				)
				(justify left)
			)
		)
		(property "Tolerance" "1%"
			(at 214.63 83.82 0)
			(effects
				(font
					(size 1.27 1.27)
				)
				(justify left bottom)
				(hide yes)
			)
		)
		(pin "2"
		)
		(pin "1"
		)
		(instances
			(project "OCuLink to 10GbE adapter"
				(path ""
					(reference "R85")
					(unit 1)
				)
			)
			(project "thunderbolt-to-10gbe-adapter"
				(path ""
					(reference "R168")
					(unit 1)
				)
			)
		)
	)
	(symbol
		(lib_id "antmicroResistors0402:R_100R_0402")
		(at 165.1 137.16 90)
		(unit 1)
		(exclude_from_sim no)
		(in_bom yes)
		(on_board yes)
		(dnp no)
		(property "Reference" "R149"
			(at 166.624 133.35 90)
			(effects
				(font
					(size 1.27 1.27)
					(thickness 0.15)
				)
				(justify right)
			)
		)
		(property "Value" "R_100R_0402"
			(at 177.8 116.84 0)
			(effects
				(font
					(size 1.27 1.27)
					(thickness 0.15)
				)
				(justify left bottom)
				(hide yes)
			)
		)
		(property "Footprint" "antmicro-footprints:R_0402_1005Metric"
			(at 180.34 116.84 0)
			(effects
				(font
					(size 1.27 1.27)
					(thickness 0.15)
				)
				(justify left bottom)
				(hide yes)
			)
		)
		(property "Datasheet" "https://www.bourns.com/docs/product-datasheets/cr.pdf"
			(at 182.88 116.84 0)
			(effects
				(font
					(size 1.27 1.27)
					(thickness 0.15)
				)
				(justify left bottom)
				(hide yes)
			)
		)
		(property "Description" "SMD Chip Resistor, 100 ohm, ± 1%, 62.5 mW, 0402 [1005 Metric], Thick Film, General Purpose"
			(at 165.1 137.16 0)
			(effects
				(font
					(size 1.27 1.27)
				)
				(hide yes)
			)
		)
		(property "MPN" "CR0402-FX-1000GLF"
			(at 185.42 116.84 0)
			(effects
				(font
					(size 1.27 1.27)
					(thickness 0.15)
				)
				(justify left bottom)
				(hide yes)
			)
		)
		(property "Manufacturer" "Bourns"
			(at 187.96 116.84 0)
			(effects
				(font
					(size 1.27 1.27)
					(thickness 0.15)
				)
				(justify left bottom)
				(hide yes)
			)
		)
		(property "License" "Apache-2.0"
			(at 190.5 116.84 0)
			(effects
				(font
					(size 1.27 1.27)
					(thickness 0.15)
				)
				(justify left bottom)
				(hide yes)
			)
		)
		(property "Author" "Antmicro"
			(at 193.04 116.84 0)
			(effects
				(font
					(size 1.27 1.27)
					(thickness 0.15)
				)
				(justify left bottom)
				(hide yes)
			)
		)
		(property "Val" "100R"
			(at 166.624 135.89 90)
			(effects
				(font
					(size 1.27 1.27)
					(thickness 0.15)
				)
				(justify right)
			)
		)
		(property "Tolerance" "1%"
			(at 175.26 116.84 0)
			(effects
				(font
					(size 1.27 1.27)
				)
				(justify left bottom)
				(hide yes)
			)
		)
		(pin "2"
		)
		(pin "1"
		)
		(instances
			(project "OCuLink to 10GbE adapter"
				(path ""
					(reference "R106")
					(unit 1)
				)
			)
			(project "thunderbolt-to-10gbe-adapter"
				(path ""
					(reference "R149")
					(unit 1)
				)
			)
		)
	)
	(symbol
		(lib_id "antmicroResistors0402:R_100R_0402")
		(at 99.06 240.03 0)
		(unit 1)
		(exclude_from_sim no)
		(in_bom yes)
		(on_board yes)
		(dnp no)
		(property "Reference" "R140"
			(at 99.06 238.76 0)
			(effects
				(font
					(size 1.27 1.27)
					(thickness 0.15)
				)
				(justify right)
			)
		)
		(property "Value" "R_100R_0402"
			(at 119.38 252.73 0)
			(effects
				(font
					(size 1.27 1.27)
					(thickness 0.15)
				)
				(justify left bottom)
				(hide yes)
			)
		)
		(property "Footprint" "antmicro-footprints:R_0402_1005Metric"
			(at 119.38 255.27 0)
			(effects
				(font
					(size 1.27 1.27)
					(thickness 0.15)
				)
				(justify left bottom)
				(hide yes)
			)
		)
		(property "Datasheet" "https://www.bourns.com/docs/product-datasheets/cr.pdf"
			(at 119.38 257.81 0)
			(effects
				(font
					(size 1.27 1.27)
					(thickness 0.15)
				)
				(justify left bottom)
				(hide yes)
			)
		)
		(property "Description" "SMD Chip Resistor, 100 ohm, ± 1%, 62.5 mW, 0402 [1005 Metric], Thick Film, General Purpose"
			(at 119.38 270.51 0)
			(effects
				(font
					(size 1.27 1.27)
				)
				(justify left bottom)
				(hide yes)
			)
		)
		(property "MPN" "CR0402-FX-1000GLF"
			(at 119.38 260.35 0)
			(effects
				(font
					(size 1.27 1.27)
					(thickness 0.15)
				)
				(justify left bottom)
				(hide yes)
			)
		)
		(property "Manufacturer" "Bourns"
			(at 119.38 262.89 0)
			(effects
				(font
					(size 1.27 1.27)
					(thickness 0.15)
				)
				(justify left bottom)
				(hide yes)
			)
		)
		(property "License" "Apache-2.0"
			(at 119.38 265.43 0)
			(effects
				(font
					(size 1.27 1.27)
					(thickness 0.15)
				)
				(justify left bottom)
				(hide yes)
			)
		)
		(property "Author" "Antmicro"
			(at 119.38 267.97 0)
			(effects
				(font
					(size 1.27 1.27)
					(thickness 0.15)
				)
				(justify left bottom)
				(hide yes)
			)
		)
		(property "Val" "100R"
			(at 104.14 238.76 0)
			(effects
				(font
					(size 1.27 1.27)
					(thickness 0.15)
				)
				(justify left)
			)
		)
		(property "Tolerance" "1%"
			(at 119.38 250.19 0)
			(effects
				(font
					(size 1.27 1.27)
				)
				(justify left bottom)
				(hide yes)
			)
		)
		(pin "2"
		)
		(pin "1"
		)
		(instances
			(project "OCuLink to 10GbE adapter"
				(path ""
					(reference "R50")
					(unit 1)
				)
			)
			(project "thunderbolt-to-10gbe-adapter"
				(path ""
					(reference "R140")
					(unit 1)
				)
			)
		)
	)
	(symbol
		(lib_id "antmicroLogicBuffersDriversReceiversTransceivers:74LVC1G07_SOT-753")
		(at 85.09 125.73 0)
		(unit 1)
		(exclude_from_sim no)
		(in_bom yes)
		(on_board yes)
		(dnp no)
		(fields_autoplaced yes)
		(property "Reference" "U15"
			(at 92.71 118.11 0)
			(effects
				(font
					(size 1.27 1.27)
					(thickness 0.15)
				)
			)
		)
		(property "Value" "74LVC1G07_SOT-753"
			(at 115.57 125.73 0)
			(effects
				(font
					(size 1.27 1.27)
					(thickness 0.15)
				)
				(justify left bottom)
				(hide yes)
			)
		)
		(property "Footprint" "antmicro-footprints:SOT-753"
			(at 115.57 128.27 0)
			(effects
				(font
					(size 1.27 1.27)
					(thickness 0.15)
				)
				(justify left bottom)
				(hide yes)
			)
		)
		(property "Datasheet" "https://www.mouser.com/datasheet/2/916/74LVC1G07-1529858.pdf"
			(at 115.57 130.81 0)
			(effects
				(font
					(size 1.27 1.27)
					(thickness 0.15)
				)
				(justify left bottom)
				(hide yes)
			)
		)
		(property "Description" "Buffer, 74LVC1G07, 1.65 V to 5.5 V, SC-74A-5"
			(at 85.09 125.73 0)
			(effects
				(font
					(size 1.27 1.27)
				)
				(hide yes)
			)
		)
		(property "MPN" "74LVC1G07GV,125"
			(at 92.71 120.65 0)
			(effects
				(font
					(size 1.27 1.27)
					(thickness 0.15)
				)
			)
		)
		(property "Manufacturer" "Nexperia"
			(at 115.57 135.89 0)
			(effects
				(font
					(size 1.27 1.27)
					(thickness 0.15)
				)
				(justify left bottom)
				(hide yes)
			)
		)
		(property "Author" "Antmicro"
			(at 115.57 138.43 0)
			(effects
				(font
					(size 1.27 1.27)
					(thickness 0.15)
				)
				(justify left bottom)
				(hide yes)
			)
		)
		(property "License" "Apache-2.0"
			(at 115.57 140.97 0)
			(effects
				(font
					(size 1.27 1.27)
					(thickness 0.15)
				)
				(justify left bottom)
				(hide yes)
			)
		)
		(pin "4"
		)
		(pin "5"
		)
		(pin "2"
		)
		(pin "1"
		)
		(pin "3"
		)
		(instances
			(project ""
				(path ""
					(reference "U10")
					(unit 1)
				)
			)
			(project "thunderbolt-to-10gbe-adapter"
				(path ""
					(reference "U15")
					(unit 1)
				)
			)
		)
	)
	(symbol
		(lib_id "antmicroResistors0402:R_1k_0402")
		(at 172.72 251.46 90)
		(unit 1)
		(exclude_from_sim no)
		(in_bom yes)
		(on_board yes)
		(dnp no)
		(property "Reference" "R153"
			(at 174.244 247.65 90)
			(effects
				(font
					(size 1.27 1.27)
					(thickness 0.15)
				)
				(justify right)
			)
		)
		(property "Value" "R_1k_0402"
			(at 185.42 231.14 0)
			(effects
				(font
					(size 1.27 1.27)
					(thickness 0.15)
				)
				(justify left bottom)
				(hide yes)
			)
		)
		(property "Footprint" "antmicro-footprints:R_0402_1005Metric"
			(at 187.96 231.14 0)
			(effects
				(font
					(size 1.27 1.27)
					(thickness 0.15)
				)
				(justify left bottom)
				(hide yes)
			)
		)
		(property "Datasheet" "https://www.bourns.com/docs/product-datasheets/cr.pdf"
			(at 190.5 231.14 0)
			(effects
				(font
					(size 1.27 1.27)
					(thickness 0.15)
				)
				(justify left bottom)
				(hide yes)
			)
		)
		(property "Description" "SMD Chip Resistor, 1 kohm, ± 1%, 63 mW, 0402 [1005 Metric], Thick Film, General Purpose"
			(at 172.72 251.46 0)
			(effects
				(font
					(size 1.27 1.27)
				)
				(hide yes)
			)
		)
		(property "MPN" "CR0402-FX-1001GLF"
			(at 193.04 231.14 0)
			(effects
				(font
					(size 1.27 1.27)
					(thickness 0.15)
				)
				(justify left bottom)
				(hide yes)
			)
		)
		(property "Manufacturer" "Bourns"
			(at 195.58 231.14 0)
			(effects
				(font
					(size 1.27 1.27)
					(thickness 0.15)
				)
				(justify left bottom)
				(hide yes)
			)
		)
		(property "License" "Apache-2.0"
			(at 198.12 231.14 0)
			(effects
				(font
					(size 1.27 1.27)
					(thickness 0.15)
				)
				(justify left bottom)
				(hide yes)
			)
		)
		(property "Author" "Antmicro"
			(at 200.66 231.14 0)
			(effects
				(font
					(size 1.27 1.27)
					(thickness 0.15)
				)
				(justify left bottom)
				(hide yes)
			)
		)
		(property "Val" "1k"
			(at 174.244 250.19 90)
			(effects
				(font
					(size 1.27 1.27)
					(thickness 0.15)
				)
				(justify right)
			)
		)
		(property "Tolerance" "1%"
			(at 182.88 231.14 0)
			(effects
				(font
					(size 1.27 1.27)
				)
				(justify left bottom)
				(hide yes)
			)
		)
		(pin "1"
		)
		(pin "2"
		)
		(instances
			(project "OCuLink to 10GbE adapter"
				(path ""
					(reference "R119")
					(unit 1)
				)
			)
			(project "thunderbolt-to-10gbe-adapter"
				(path ""
					(reference "R153")
					(unit 1)
				)
			)
		)
	)
	(symbol
		(lib_id "antmicropower:GND")
		(at 107.95 245.11 0)
		(mirror y)
		(unit 1)
		(exclude_from_sim no)
		(in_bom yes)
		(on_board yes)
		(dnp no)
		(property "Reference" "#PWR0381"
			(at 99.06 247.65 0)
			(effects
				(font
					(size 1.27 1.27)
					(thickness 0.15)
				)
				(justify left bottom)
				(hide yes)
			)
		)
		(property "Value" "GND"
			(at 107.95 248.92 0)
			(effects
				(font
					(size 1.27 1.27)
					(thickness 0.15)
				)
			)
		)
		(property "Footprint" ""
			(at 99.06 252.73 0)
			(effects
				(font
					(size 1.27 1.27)
					(thickness 0.15)
				)
				(justify left bottom)
				(hide yes)
			)
		)
		(property "Datasheet" ""
			(at 99.06 257.81 0)
			(effects
				(font
					(size 1.27 1.27)
					(thickness 0.15)
				)
				(justify left bottom)
				(hide yes)
			)
		)
		(property "Description" ""
			(at 107.95 245.11 0)
			(effects
				(font
					(size 1.27 1.27)
				)
				(hide yes)
			)
		)
		(property "Author" "Antmicro"
			(at 99.06 252.73 0)
			(effects
				(font
					(size 1.27 1.27)
					(thickness 0.15)
				)
				(justify left bottom)
				(hide yes)
			)
		)
		(property "License" "Apache-2.0"
			(at 99.06 255.27 0)
			(effects
				(font
					(size 1.27 1.27)
					(thickness 0.15)
				)
				(justify left bottom)
				(hide yes)
			)
		)
		(pin "1"
		)
		(instances
			(project "OCuLink to 10GbE adapter"
				(path ""
					(reference "#PWR0104")
					(unit 1)
				)
			)
			(project "thunderbolt-to-10gbe-adapter"
				(path ""
					(reference "#PWR0381")
					(unit 1)
				)
			)
		)
	)
	(symbol
		(lib_id "antmicroCapacitors0402:C_1u_25V_0402")
		(at 154.94 137.16 90)
		(unit 1)
		(exclude_from_sim no)
		(in_bom yes)
		(on_board yes)
		(dnp no)
		(property "Reference" "C279"
			(at 156.972 133.35 90)
			(effects
				(font
					(size 1.27 1.27)
					(thickness 0.15)
				)
				(justify right)
			)
		)
		(property "Value" "C_1u_25V_0402"
			(at 165.1 116.84 0)
			(effects
				(font
					(size 1.27 1.27)
					(thickness 0.15)
				)
				(justify left bottom)
				(hide yes)
			)
		)
		(property "Footprint" "antmicro-footprints:C_0402_1005Metric"
			(at 167.64 116.84 0)
			(effects
				(font
					(size 1.27 1.27)
					(thickness 0.15)
				)
				(justify left bottom)
				(hide yes)
			)
		)
		(property "Datasheet" "https://www.murata.com/products/productdetail?partno=GRM155R61E105KE11%23"
			(at 170.18 116.84 0)
			(effects
				(font
					(size 1.27 1.27)
					(thickness 0.15)
				)
				(justify left bottom)
				(hide yes)
			)
		)
		(property "Description" "SMD Multilayer Ceramic Capacitor, 1 µF, 25 V, 0402 [1005 Metric], ± 10%, X5R, GRM Series"
			(at 154.94 137.16 0)
			(effects
				(font
					(size 1.27 1.27)
				)
				(hide yes)
			)
		)
		(property "MPN" "GRM155R61E105KE11J"
			(at 172.72 116.84 0)
			(effects
				(font
					(size 1.27 1.27)
					(thickness 0.15)
				)
				(justify left bottom)
				(hide yes)
			)
		)
		(property "Manufacturer" "Murata"
			(at 175.26 116.84 0)
			(effects
				(font
					(size 1.27 1.27)
					(thickness 0.15)
				)
				(justify left bottom)
				(hide yes)
			)
		)
		(property "License" "Apache-2.0"
			(at 177.8 116.84 0)
			(effects
				(font
					(size 1.27 1.27)
					(thickness 0.15)
				)
				(justify left bottom)
				(hide yes)
			)
		)
		(property "Author" "Antmicro"
			(at 180.34 116.84 0)
			(effects
				(font
					(size 1.27 1.27)
					(thickness 0.15)
				)
				(justify left bottom)
				(hide yes)
			)
		)
		(property "Val" "1u"
			(at 156.972 135.89 90)
			(effects
				(font
					(size 1.27 1.27)
					(thickness 0.15)
				)
				(justify right)
			)
		)
		(property "Voltage" "25V"
			(at 182.88 116.84 0)
			(effects
				(font
					(size 1.27 1.27)
				)
				(justify left bottom)
				(hide yes)
			)
		)
		(property "Dielectric" "X5R"
			(at 185.42 116.84 0)
			(effects
				(font
					(size 1.27 1.27)
				)
				(justify left bottom)
				(hide yes)
			)
		)
		(pin "2"
		)
		(pin "1"
		)
		(instances
			(project "oculink-to-10gbe-adapter"
				(path ""
					(reference "C211")
					(unit 1)
				)
			)
			(project "thunderbolt-to-10gbe-adapter"
				(path ""
					(reference "C279")
					(unit 1)
				)
			)
		)
	)
	(symbol
		(lib_id "antmicroResistors0402:R_2k_0402")
		(at 204.47 193.04 90)
		(unit 1)
		(exclude_from_sim no)
		(in_bom yes)
		(on_board yes)
		(dnp no)
		(property "Reference" "R173"
			(at 205.994 189.23 90)
			(effects
				(font
					(size 1.27 1.27)
					(thickness 0.15)
				)
				(justify right)
			)
		)
		(property "Value" "R_2k_0402"
			(at 217.17 172.72 0)
			(effects
				(font
					(size 1.27 1.27)
					(thickness 0.15)
				)
				(justify left bottom)
				(hide yes)
			)
		)
		(property "Footprint" "antmicro-footprints:R_0402_1005Metric"
			(at 219.71 172.72 0)
			(effects
				(font
					(size 1.27 1.27)
					(thickness 0.15)
				)
				(justify left bottom)
				(hide yes)
			)
		)
		(property "Datasheet" "https://www.bourns.com/docs/product-datasheets/cr.pdf"
			(at 222.25 172.72 0)
			(effects
				(font
					(size 1.27 1.27)
					(thickness 0.15)
				)
				(justify left bottom)
				(hide yes)
			)
		)
		(property "Description" "SMD Chip Resistor, 2 kohm, ± 1%, 62.5 mW, 0402 [1005 Metric], Thick Film, General Purpose"
			(at 204.47 193.04 0)
			(effects
				(font
					(size 1.27 1.27)
				)
				(hide yes)
			)
		)
		(property "MPN" "CR0402-FX-2001GLF"
			(at 224.79 172.72 0)
			(effects
				(font
					(size 1.27 1.27)
					(thickness 0.15)
				)
				(justify left bottom)
				(hide yes)
			)
		)
		(property "Manufacturer" "Bourns"
			(at 227.33 172.72 0)
			(effects
				(font
					(size 1.27 1.27)
					(thickness 0.15)
				)
				(justify left bottom)
				(hide yes)
			)
		)
		(property "License" "Apache-2.0"
			(at 229.87 172.72 0)
			(effects
				(font
					(size 1.27 1.27)
					(thickness 0.15)
				)
				(justify left bottom)
				(hide yes)
			)
		)
		(property "Author" "Antmicro"
			(at 232.41 172.72 0)
			(effects
				(font
					(size 1.27 1.27)
					(thickness 0.15)
				)
				(justify left bottom)
				(hide yes)
			)
		)
		(property "Val" "2k"
			(at 205.994 191.77 90)
			(effects
				(font
					(size 1.27 1.27)
					(thickness 0.15)
				)
				(justify right)
			)
		)
		(property "Tolerance" "1%"
			(at 214.63 172.72 0)
			(effects
				(font
					(size 1.27 1.27)
				)
				(justify left bottom)
				(hide yes)
			)
		)
		(pin "1"
		)
		(pin "2"
		)
		(instances
			(project "OCuLink to 10GbE adapter"
				(path ""
					(reference "R115")
					(unit 1)
				)
			)
			(project "thunderbolt-to-10gbe-adapter"
				(path ""
					(reference "R173")
					(unit 1)
				)
			)
		)
	)
	(symbol
		(lib_id "antmicropower:+3V3")
		(at 151.13 101.6 0)
		(unit 1)
		(exclude_from_sim no)
		(in_bom yes)
		(on_board yes)
		(dnp no)
		(property "Reference" "#PWR0388"
			(at 166.37 101.6 0)
			(effects
				(font
					(size 1.27 1.27)
					(thickness 0.15)
				)
				(justify left bottom)
				(hide yes)
			)
		)
		(property "Value" "+3V3"
			(at 151.13 97.79 0)
			(effects
				(font
					(size 1.27 1.27)
					(thickness 0.15)
				)
			)
		)
		(property "Footprint" ""
			(at 166.37 109.22 0)
			(effects
				(font
					(size 1.27 1.27)
					(thickness 0.15)
				)
				(justify left bottom)
				(hide yes)
			)
		)
		(property "Datasheet" ""
			(at 166.37 111.76 0)
			(effects
				(font
					(size 1.27 1.27)
					(thickness 0.15)
				)
				(justify left bottom)
				(hide yes)
			)
		)
		(property "Description" ""
			(at 151.13 101.6 0)
			(effects
				(font
					(size 1.27 1.27)
				)
				(hide yes)
			)
		)
		(property "Author" "Antmicro"
			(at 166.37 104.14 0)
			(effects
				(font
					(size 1.27 1.27)
					(thickness 0.15)
				)
				(justify left bottom)
				(hide yes)
			)
		)
		(property "License" "Apache-2.0"
			(at 166.37 106.68 0)
			(effects
				(font
					(size 1.27 1.27)
					(thickness 0.15)
				)
				(justify left bottom)
				(hide yes)
			)
		)
		(pin "1"
		)
		(instances
			(project "OCuLink to 10GbE adapter"
				(path ""
					(reference "#PWR0264")
					(unit 1)
				)
			)
			(project "thunderbolt-to-10gbe-adapter"
				(path ""
					(reference "#PWR0388")
					(unit 1)
				)
			)
		)
	)
	(symbol
		(lib_id "antmicroResistors0402:R_10k_0402")
		(at 189.23 86.36 90)
		(unit 1)
		(exclude_from_sim no)
		(in_bom yes)
		(on_board yes)
		(dnp no)
		(property "Reference" "R161"
			(at 190.754 82.55 90)
			(effects
				(font
					(size 1.27 1.27)
					(thickness 0.15)
				)
				(justify right)
			)
		)
		(property "Value" "R_10k_0402"
			(at 201.93 66.04 0)
			(effects
				(font
					(size 1.27 1.27)
					(thickness 0.15)
				)
				(justify left bottom)
				(hide yes)
			)
		)
		(property "Footprint" "antmicro-footprints:R_0402_1005Metric"
			(at 204.47 66.04 0)
			(effects
				(font
					(size 1.27 1.27)
					(thickness 0.15)
				)
				(justify left bottom)
				(hide yes)
			)
		)
		(property "Datasheet" "https://www.bourns.com/docs/product-datasheets/cr.pdf"
			(at 207.01 66.04 0)
			(effects
				(font
					(size 1.27 1.27)
					(thickness 0.15)
				)
				(justify left bottom)
				(hide yes)
			)
		)
		(property "Description" "SMD Chip Resistor, 10 kohm, ± 1%, 62.5 mW, 0402 [1005 Metric], Thick Film, General Purpose"
			(at 189.23 86.36 0)
			(effects
				(font
					(size 1.27 1.27)
				)
				(hide yes)
			)
		)
		(property "MPN" "CR0402-FX-1002GLF"
			(at 209.55 66.04 0)
			(effects
				(font
					(size 1.27 1.27)
					(thickness 0.15)
				)
				(justify left bottom)
				(hide yes)
			)
		)
		(property "Manufacturer" "Bourns"
			(at 212.09 66.04 0)
			(effects
				(font
					(size 1.27 1.27)
					(thickness 0.15)
				)
				(justify left bottom)
				(hide yes)
			)
		)
		(property "License" "Apache-2.0"
			(at 214.63 66.04 0)
			(effects
				(font
					(size 1.27 1.27)
					(thickness 0.15)
				)
				(justify left bottom)
				(hide yes)
			)
		)
		(property "Author" "Antmicro"
			(at 217.17 66.04 0)
			(effects
				(font
					(size 1.27 1.27)
					(thickness 0.15)
				)
				(justify left bottom)
				(hide yes)
			)
		)
		(property "Val" "10k"
			(at 190.754 85.09 90)
			(effects
				(font
					(size 1.27 1.27)
					(thickness 0.15)
				)
				(justify right)
			)
		)
		(property "Tolerance" "1%"
			(at 199.39 66.04 0)
			(effects
				(font
					(size 1.27 1.27)
				)
				(justify left bottom)
				(hide yes)
			)
		)
		(pin "2"
		)
		(pin "1"
		)
		(instances
			(project ""
				(path ""
					(reference "R90")
					(unit 1)
				)
			)
			(project "thunderbolt-to-10gbe-adapter"
				(path ""
					(reference "R161")
					(unit 1)
				)
			)
		)
	)
	(symbol
		(lib_id "antmicropower:GND")
		(at 138.43 189.23 0)
		(mirror y)
		(unit 1)
		(exclude_from_sim no)
		(in_bom yes)
		(on_board yes)
		(dnp no)
		(property "Reference" "#PWR0385"
			(at 129.54 191.77 0)
			(effects
				(font
					(size 1.27 1.27)
					(thickness 0.15)
				)
				(justify left bottom)
				(hide yes)
			)
		)
		(property "Value" "GND"
			(at 138.43 193.04 0)
			(effects
				(font
					(size 1.27 1.27)
					(thickness 0.15)
				)
			)
		)
		(property "Footprint" ""
			(at 129.54 196.85 0)
			(effects
				(font
					(size 1.27 1.27)
					(thickness 0.15)
				)
				(justify left bottom)
				(hide yes)
			)
		)
		(property "Datasheet" ""
			(at 129.54 201.93 0)
			(effects
				(font
					(size 1.27 1.27)
					(thickness 0.15)
				)
				(justify left bottom)
				(hide yes)
			)
		)
		(property "Description" ""
			(at 138.43 189.23 0)
			(effects
				(font
					(size 1.27 1.27)
				)
				(hide yes)
			)
		)
		(property "Author" "Antmicro"
			(at 129.54 196.85 0)
			(effects
				(font
					(size 1.27 1.27)
					(thickness 0.15)
				)
				(justify left bottom)
				(hide yes)
			)
		)
		(property "License" "Apache-2.0"
			(at 129.54 199.39 0)
			(effects
				(font
					(size 1.27 1.27)
					(thickness 0.15)
				)
				(justify left bottom)
				(hide yes)
			)
		)
		(pin "1"
		)
		(instances
			(project "OCuLink to 10GbE adapter"
				(path ""
					(reference "#PWR0109")
					(unit 1)
				)
			)
			(project "thunderbolt-to-10gbe-adapter"
				(path ""
					(reference "#PWR0385")
					(unit 1)
				)
			)
		)
	)
	(symbol
		(lib_id "antmicropower:GND")
		(at 314.96 139.7 0)
		(unit 1)
		(exclude_from_sim no)
		(in_bom yes)
		(on_board yes)
		(dnp no)
		(property "Reference" "#PWR0412"
			(at 323.85 142.24 0)
			(effects
				(font
					(size 1.27 1.27)
					(thickness 0.15)
				)
				(justify left bottom)
				(hide yes)
			)
		)
		(property "Value" "GND"
			(at 314.96 143.51 0)
			(effects
				(font
					(size 1.27 1.27)
					(thickness 0.15)
				)
			)
		)
		(property "Footprint" ""
			(at 323.85 147.32 0)
			(effects
				(font
					(size 1.27 1.27)
					(thickness 0.15)
				)
				(justify left bottom)
				(hide yes)
			)
		)
		(property "Datasheet" ""
			(at 323.85 152.4 0)
			(effects
				(font
					(size 1.27 1.27)
					(thickness 0.15)
				)
				(justify left bottom)
				(hide yes)
			)
		)
		(property "Description" ""
			(at 314.96 139.7 0)
			(effects
				(font
					(size 1.27 1.27)
				)
				(hide yes)
			)
		)
		(property "Author" "Antmicro"
			(at 323.85 147.32 0)
			(effects
				(font
					(size 1.27 1.27)
					(thickness 0.15)
				)
				(justify left bottom)
				(hide yes)
			)
		)
		(property "License" "Apache-2.0"
			(at 323.85 149.86 0)
			(effects
				(font
					(size 1.27 1.27)
					(thickness 0.15)
				)
				(justify left bottom)
				(hide yes)
			)
		)
		(pin "1"
		)
		(instances
			(project "OCuLink to 10GbE adapter"
				(path ""
					(reference "#PWR0274")
					(unit 1)
				)
			)
			(project "thunderbolt-to-10gbe-adapter"
				(path ""
					(reference "#PWR0412")
					(unit 1)
				)
			)
		)
	)
	(symbol
		(lib_id "antmicroTestPoints:TP_0.75mm_SMD")
		(at 133.35 76.2 180)
		(unit 1)
		(exclude_from_sim no)
		(in_bom no)
		(on_board yes)
		(dnp no)
		(property "Reference" "TP28"
			(at 129.032 76.2 0)
			(effects
				(font
					(size 1.27 1.27)
					(thickness 0.15)
				)
				(justify left)
			)
		)
		(property "Value" "TP_0.75mm_SMD"
			(at 123.19 72.39 0)
			(effects
				(font
					(size 1.27 1.27)
					(thickness 0.15)
				)
				(justify left bottom)
				(hide yes)
			)
		)
		(property "Footprint" "antmicro-footprints:TP_SMD_0.75mm"
			(at 123.19 69.85 0)
			(effects
				(font
					(size 1.27 1.27)
					(thickness 0.15)
				)
				(justify left bottom)
				(hide yes)
			)
		)
		(property "Datasheet" ""
			(at 115.57 63.5 0)
			(effects
				(font
					(size 1.27 1.27)
					(thickness 0.15)
				)
				(justify left bottom)
				(hide yes)
			)
		)
		(property "Description" "SMT test point"
			(at 133.35 76.2 0)
			(effects
				(font
					(size 1.27 1.27)
				)
				(hide yes)
			)
		)
		(property "MPN" ""
			(at 122.555 64.77 0)
			(effects
				(font
					(size 1.27 1.27)
					(thickness 0.15)
				)
				(justify left bottom)
				(hide yes)
			)
		)
		(property "Manufacturer" ""
			(at 122.555 69.85 0)
			(effects
				(font
					(size 1.27 1.27)
					(thickness 0.15)
				)
				(justify left bottom)
				(hide yes)
			)
		)
		(property "Author" "Antmicro"
			(at 123.19 67.31 0)
			(effects
				(font
					(size 1.27 1.27)
					(thickness 0.15)
				)
				(justify left bottom)
				(hide yes)
			)
		)
		(property "License" "Apache-2.0"
			(at 123.19 64.77 0)
			(effects
				(font
					(size 1.27 1.27)
					(thickness 0.15)
				)
				(justify left bottom)
				(hide yes)
			)
		)
		(pin "1"
		)
		(instances
			(project "OCuLink to 10GbE adapter"
				(path ""
					(reference "TP8")
					(unit 1)
				)
			)
			(project "thunderbolt-to-10gbe-adapter"
				(path ""
					(reference "TP28")
					(unit 1)
				)
			)
		)
	)
	(symbol
		(lib_id "antmicroCapacitors0402:C_100n_0402")
		(at 102.87 186.69 270)
		(mirror x)
		(unit 1)
		(exclude_from_sim no)
		(in_bom yes)
		(on_board yes)
		(dnp no)
		(property "Reference" "C275"
			(at 100.838 182.88 90)
			(effects
				(font
					(size 1.27 1.27)
					(thickness 0.15)
				)
				(justify right)
			)
		)
		(property "Value" "C_100n_0402"
			(at 80.01 171.45 0)
			(effects
				(font
					(size 1.27 1.27)
					(thickness 0.15)
				)
				(justify left bottom)
				(hide yes)
			)
		)
		(property "Footprint" "antmicro-footprints:C_0402_1005Metric"
			(at 77.47 171.45 0)
			(effects
				(font
					(size 1.27 1.27)
					(thickness 0.15)
				)
				(justify left bottom)
				(hide yes)
			)
		)
		(property "Datasheet" "https://www.murata.com/products/productdetail?partno=GRM155R61H104KE14%23"
			(at 74.93 171.45 0)
			(effects
				(font
					(size 1.27 1.27)
					(thickness 0.15)
				)
				(justify left bottom)
				(hide yes)
			)
		)
		(property "Description" "SMD Multilayer Ceramic Capacitor, 0.1 µF, 50 V, 0402 [1005 Metric], ± 10%, X5R, GRM Series"
			(at 102.87 186.69 0)
			(effects
				(font
					(size 1.27 1.27)
				)
				(hide yes)
			)
		)
		(property "MPN" "GRM155R61H104KE14D"
			(at 72.39 171.45 0)
			(effects
				(font
					(size 1.27 1.27)
					(thickness 0.15)
				)
				(justify left bottom)
				(hide yes)
			)
		)
		(property "Val" "100n"
			(at 100.838 185.42 90)
			(effects
				(font
					(size 1.27 1.27)
					(thickness 0.15)
				)
				(justify right)
			)
		)
		(property "Voltage" "50V"
			(at 92.71 171.45 0)
			(effects
				(font
					(size 1.27 1.27)
					(thickness 0.15)
				)
				(justify left bottom)
				(hide yes)
			)
		)
		(property "Dielectric" "X5R"
			(at 90.17 171.45 0)
			(effects
				(font
					(size 1.27 1.27)
					(thickness 0.15)
				)
				(justify left bottom)
				(hide yes)
			)
		)
		(property "Manufacturer" "Murata"
			(at 87.63 171.45 0)
			(effects
				(font
					(size 1.27 1.27)
					(thickness 0.15)
				)
				(justify left bottom)
				(hide yes)
			)
		)
		(property "License" "Apache-2.0"
			(at 85.09 171.45 0)
			(effects
				(font
					(size 1.27 1.27)
					(thickness 0.15)
				)
				(justify left bottom)
				(hide yes)
			)
		)
		(property "Author" "Antmicro"
			(at 82.55 171.45 0)
			(effects
				(font
					(size 1.27 1.27)
					(thickness 0.15)
				)
				(justify left bottom)
				(hide yes)
			)
		)
		(pin "2"
		)
		(pin "1"
		)
		(instances
			(project "OCuLink to 10GbE adapter"
				(path ""
					(reference "C77")
					(unit 1)
				)
			)
			(project "thunderbolt-to-10gbe-adapter"
				(path ""
					(reference "C275")
					(unit 1)
				)
			)
		)
	)
	(symbol
		(lib_id "antmicroTestPoints:TP_0.75mm_SMD")
		(at 210.82 238.76 180)
		(unit 1)
		(exclude_from_sim no)
		(in_bom no)
		(on_board yes)
		(dnp no)
		(property "Reference" "TP33"
			(at 206.502 238.76 0)
			(effects
				(font
					(size 1.27 1.27)
					(thickness 0.15)
				)
				(justify left)
			)
		)
		(property "Value" "TP_0.75mm_SMD"
			(at 200.66 234.95 0)
			(effects
				(font
					(size 1.27 1.27)
					(thickness 0.15)
				)
				(justify left bottom)
				(hide yes)
			)
		)
		(property "Footprint" "antmicro-footprints:TP_SMD_0.75mm"
			(at 200.66 232.41 0)
			(effects
				(font
					(size 1.27 1.27)
					(thickness 0.15)
				)
				(justify left bottom)
				(hide yes)
			)
		)
		(property "Datasheet" ""
			(at 193.04 226.06 0)
			(effects
				(font
					(size 1.27 1.27)
					(thickness 0.15)
				)
				(justify left bottom)
				(hide yes)
			)
		)
		(property "Description" "SMT test point"
			(at 210.82 238.76 0)
			(effects
				(font
					(size 1.27 1.27)
				)
				(hide yes)
			)
		)
		(property "MPN" ""
			(at 200.025 227.33 0)
			(effects
				(font
					(size 1.27 1.27)
					(thickness 0.15)
				)
				(justify left bottom)
				(hide yes)
			)
		)
		(property "Manufacturer" ""
			(at 200.025 232.41 0)
			(effects
				(font
					(size 1.27 1.27)
					(thickness 0.15)
				)
				(justify left bottom)
				(hide yes)
			)
		)
		(property "Author" "Antmicro"
			(at 200.66 229.87 0)
			(effects
				(font
					(size 1.27 1.27)
					(thickness 0.15)
				)
				(justify left bottom)
				(hide yes)
			)
		)
		(property "License" "Apache-2.0"
			(at 200.66 227.33 0)
			(effects
				(font
					(size 1.27 1.27)
					(thickness 0.15)
				)
				(justify left bottom)
				(hide yes)
			)
		)
		(pin "1"
		)
		(instances
			(project "OCuLink to 10GbE adapter"
				(path ""
					(reference "TP12")
					(unit 1)
				)
			)
			(project "thunderbolt-to-10gbe-adapter"
				(path ""
					(reference "TP33")
					(unit 1)
				)
			)
		)
	)
	(symbol
		(lib_id "antmicroResistors0402:R_8k2_0402")
		(at 314.96 137.16 90)
		(unit 1)
		(exclude_from_sim no)
		(in_bom yes)
		(on_board yes)
		(dnp no)
		(property "Reference" "R183"
			(at 316.484 133.35 90)
			(effects
				(font
					(size 1.27 1.27)
					(thickness 0.15)
				)
				(justify right)
			)
		)
		(property "Value" "R_8k2_0402"
			(at 327.66 116.84 0)
			(effects
				(font
					(size 1.27 1.27)
					(thickness 0.15)
				)
				(justify left bottom)
				(hide yes)
			)
		)
		(property "Footprint" "antmicro-footprints:R_0402_1005Metric"
			(at 330.2 116.84 0)
			(effects
				(font
					(size 1.27 1.27)
					(thickness 0.15)
				)
				(justify left bottom)
				(hide yes)
			)
		)
		(property "Datasheet" "https://www.bourns.com/docs/product-datasheets/cr.pdf"
			(at 332.74 116.84 0)
			(effects
				(font
					(size 1.27 1.27)
					(thickness 0.15)
				)
				(justify left bottom)
				(hide yes)
			)
		)
		(property "Description" "SMD Chip Resistor"
			(at 314.96 137.16 0)
			(effects
				(font
					(size 1.27 1.27)
				)
				(hide yes)
			)
		)
		(property "MPN" "CR0402-FX-8201GLF"
			(at 335.28 116.84 0)
			(effects
				(font
					(size 1.27 1.27)
					(thickness 0.15)
				)
				(justify left bottom)
				(hide yes)
			)
		)
		(property "Manufacturer" "Bourns"
			(at 337.82 116.84 0)
			(effects
				(font
					(size 1.27 1.27)
					(thickness 0.15)
				)
				(justify left bottom)
				(hide yes)
			)
		)
		(property "License" "Apache-2.0"
			(at 340.36 116.84 0)
			(effects
				(font
					(size 1.27 1.27)
					(thickness 0.15)
				)
				(justify left bottom)
				(hide yes)
			)
		)
		(property "Author" "Antmicro"
			(at 342.9 116.84 0)
			(effects
				(font
					(size 1.27 1.27)
					(thickness 0.15)
				)
				(justify left bottom)
				(hide yes)
			)
		)
		(property "Val" "8k2"
			(at 316.484 135.89 90)
			(effects
				(font
					(size 1.27 1.27)
					(thickness 0.15)
				)
				(justify right)
			)
		)
		(property "Tolerance" "1%"
			(at 325.12 116.84 0)
			(effects
				(font
					(size 1.27 1.27)
				)
				(justify left bottom)
				(hide yes)
			)
		)
		(pin "1"
		)
		(pin "2"
		)
		(instances
			(project ""
				(path ""
					(reference "R110")
					(unit 1)
				)
			)
			(project "thunderbolt-to-10gbe-adapter"
				(path ""
					(reference "R183")
					(unit 1)
				)
			)
		)
	)
	(symbol
		(lib_id "antmicropower:GND")
		(at 176.53 139.7 0)
		(unit 1)
		(exclude_from_sim no)
		(in_bom yes)
		(on_board yes)
		(dnp no)
		(property "Reference" "#PWR0397"
			(at 185.42 142.24 0)
			(effects
				(font
					(size 1.27 1.27)
					(thickness 0.15)
				)
				(justify left bottom)
				(hide yes)
			)
		)
		(property "Value" "GND"
			(at 176.53 143.51 0)
			(effects
				(font
					(size 1.27 1.27)
					(thickness 0.15)
				)
			)
		)
		(property "Footprint" ""
			(at 185.42 147.32 0)
			(effects
				(font
					(size 1.27 1.27)
					(thickness 0.15)
				)
				(justify left bottom)
				(hide yes)
			)
		)
		(property "Datasheet" ""
			(at 185.42 152.4 0)
			(effects
				(font
					(size 1.27 1.27)
					(thickness 0.15)
				)
				(justify left bottom)
				(hide yes)
			)
		)
		(property "Description" ""
			(at 176.53 139.7 0)
			(effects
				(font
					(size 1.27 1.27)
				)
				(hide yes)
			)
		)
		(property "Author" "Antmicro"
			(at 185.42 147.32 0)
			(effects
				(font
					(size 1.27 1.27)
					(thickness 0.15)
				)
				(justify left bottom)
				(hide yes)
			)
		)
		(property "License" "Apache-2.0"
			(at 185.42 149.86 0)
			(effects
				(font
					(size 1.27 1.27)
					(thickness 0.15)
				)
				(justify left bottom)
				(hide yes)
			)
		)
		(pin "1"
		)
		(instances
			(project "OCuLink to 10GbE adapter"
				(path ""
					(reference "#PWR0271")
					(unit 1)
				)
			)
			(project "thunderbolt-to-10gbe-adapter"
				(path ""
					(reference "#PWR0397")
					(unit 1)
				)
			)
		)
	)
)
